FILE_TYPE = MACRO_DRAWING;
SET COLOR_WIRE YELLOW;
SET COLOR_PROP MONO;
SET COLOR_DOT WHITE;
SET COLOR_ARC YELLOW;
SET COLOR_BODY GREEN;
SET COLOR_NOTE MONO;
SET PROP_DISPLAY VALUE;
SET PAGE_NUMBER P119;
FORCEADD OFFPAGE..4
R 2
(-7550 3650);
FORCEPROP 2 LAST $XR0 133 
J 0
(-7802 3650);
DISPLAY 0.638298 (-7802 3650);
PAINT MONO (-7802 3650);
FORCEPROP 2 LAST CDS_LIB mstr_standard
J 0
(-7550 3650);
PAINT ORANGE (-7550 3650);
DISPLAY INVISIBLE (-7550 3650);
FORCEPROP 2 LAST PATH I10
J 0
(-7500 3725);
DISPLAY 1.021277 (-7500 3725);
PAINT ORANGE (-7500 3725);
DISPLAY INVISIBLE (-7500 3725);
FORCEPROP 1 LAST OFFPAGE TRUE
J 2
(-7875 3525);
DISPLAY 0.872340 (-7875 3525);
PAINT GREEN (-7875 3525);
DISPLAY INVISIBLE (-7875 3525);
FORCEPROP 1 LAST COMMENT_BODY TRUE
J 2
(-7525 3550);
DISPLAY 0.872340 (-7525 3550);
PAINT GREEN (-7525 3550);
DISPLAY INVISIBLE (-7525 3550);
FORCEADD OFFPAGE..1
(-7550 4300);
FORCEPROP 2 LAST $XR2 146 
J 0
(-7802 4264);
DISPLAY 0.638298 (-7802 4264);
PAINT MONO (-7802 4264);
FORCEPROP 2 LAST $XR1 250 
J 0
(-7922 4300);
DISPLAY 0.638298 (-7922 4300);
PAINT MONO (-7922 4300);
FORCEPROP 2 LAST $XR0 133 
J 0
(-7802 4300);
DISPLAY 0.638298 (-7802 4300);
PAINT MONO (-7802 4300);
FORCEPROP 2 LAST CDS_LIB mstr_standard
J 0
(-7550 4300);
PAINT ORANGE (-7550 4300);
DISPLAY INVISIBLE (-7550 4300);
FORCEPROP 2 LAST PATH I101
J 0
(-7500 4375);
DISPLAY 1.021277 (-7500 4375);
PAINT ORANGE (-7500 4375);
DISPLAY INVISIBLE (-7500 4375);
FORCEPROP 1 LAST OFFPAGE TRUE
J 0
(-7225 4175);
DISPLAY 0.872340 (-7225 4175);
PAINT GREEN (-7225 4175);
DISPLAY INVISIBLE (-7225 4175);
FORCEPROP 1 LAST COMMENT_BODY TRUE
J 0
(-7425 4200);
DISPLAY 0.872340 (-7425 4200);
PAINT GREEN (-7425 4200);
DISPLAY INVISIBLE (-7425 4200);
FORCEADD LBG_CORE_QAT_EXT_D..6
(-4100 3200);
FORCEPROP 2 LASTPIN (-5900 4400) $PN V1
J 2
(-5910 4410);
DISPLAY 0.617021 (-5910 4410);
PAINT ORANGE (-5910 4410);
FORCEPROP 2 LASTPIN (-5900 4100) $PN AD1
J 2
(-5910 4110);
DISPLAY 0.617021 (-5910 4110);
PAINT ORANGE (-5910 4110);
FORCEPROP 2 LASTPIN (-5900 4050) $PN T2
J 2
(-5910 4060);
DISPLAY 0.617021 (-5910 4060);
PAINT ORANGE (-5910 4060);
FORCEPROP 2 LASTPIN (-5900 4000) $PN AC4
J 2
(-5910 4010);
DISPLAY 0.617021 (-5910 4010);
PAINT ORANGE (-5910 4010);
FORCEPROP 2 LASTPIN (-5900 3600) $PN AA2
J 2
(-5910 3610);
DISPLAY 0.617021 (-5910 3610);
PAINT ORANGE (-5910 3610);
FORCEPROP 2 LASTPIN (-2300 3150) $PN BN44
J 0
(-2290 3160);
DISPLAY 0.617021 (-2290 3160);
PAINT ORANGE (-2290 3160);
FORCEPROP 2 LASTPIN (-5900 4300) $PN AE2
J 2
(-5910 4310);
DISPLAY 0.617021 (-5910 4310);
PAINT ORANGE (-5910 4310);
FORCEPROP 2 LASTPIN (-2300 4100) $PN BY31
J 0
(-2290 4110);
DISPLAY 0.617021 (-2290 4110);
PAINT ORANGE (-2290 4110);
FORCEPROP 2 LASTPIN (-2300 4400) $PN CA37
J 0
(-2290 4410);
DISPLAY 0.617021 (-2290 4410);
PAINT ORANGE (-2290 4410);
FORCEPROP 2 LASTPIN (-2300 3950) $PN BY38
J 0
(-2290 3960);
DISPLAY 0.617021 (-2290 3960);
PAINT ORANGE (-2290 3960);
FORCEPROP 2 LASTPIN (-2300 3600) $PN BV35
J 0
(-2290 3610);
DISPLAY 0.617021 (-2290 3610);
PAINT ORANGE (-2290 3610);
FORCEPROP 2 LASTPIN (-5900 3400) $PN W2
J 2
(-5910 3410);
DISPLAY 0.617021 (-5910 3410);
PAINT ORANGE (-5910 3410);
FORCEPROP 2 LASTPIN (-5900 3350) $PN N1
J 2
(-5910 3360);
DISPLAY 0.617021 (-5910 3360);
PAINT ORANGE (-5910 3360);
FORCEPROP 2 LASTPIN (-2300 3900) $PN BV38
J 0
(-2290 3910);
DISPLAY 0.617021 (-2290 3910);
PAINT ORANGE (-2290 3910);
FORCEPROP 2 LASTPIN (-5900 3750) $PN AA4
J 2
(-5910 3760);
DISPLAY 0.617021 (-5910 3760);
PAINT ORANGE (-5910 3760);
FORCEPROP 2 LASTPIN (-5900 3250) $PN N3
J 2
(-5910 3260);
DISPLAY 0.617021 (-5910 3260);
PAINT ORANGE (-5910 3260);
FORCEPROP 2 LASTPIN (-5900 4350) $PN AE4
J 2
(-5910 4360);
DISPLAY 0.617021 (-5910 4360);
PAINT ORANGE (-5910 4360);
FORCEPROP 2 LASTPIN (-2300 2950) $PN CA43
J 0
(-2290 2960);
DISPLAY 0.617021 (-2290 2960);
PAINT ORANGE (-2290 2960);
FORCEPROP 2 LASTPIN (-5900 2200) $PN BN7
J 2
(-5910 2210);
DISPLAY 0.617021 (-5910 2210);
PAINT ORANGE (-5910 2210);
FORCEPROP 2 LASTPIN (-5900 2150) $PN BR9
J 2
(-5910 2160);
DISPLAY 0.617021 (-5910 2160);
PAINT ORANGE (-5910 2160);
FORCEPROP 2 LASTPIN (-5900 2100) $PN BN15
J 2
(-5910 2110);
DISPLAY 0.617021 (-5910 2110);
PAINT ORANGE (-5910 2110);
FORCEPROP 2 LASTPIN (-5900 2050) $PN BH9
J 2
(-5910 2060);
DISPLAY 0.617021 (-5910 2060);
PAINT ORANGE (-5910 2060);
FORCEPROP 2 LASTPIN (-5900 2000) $PN BL7
J 2
(-5910 2010);
DISPLAY 0.617021 (-5910 2010);
PAINT ORANGE (-5910 2010);
FORCEPROP 2 LASTPIN (-5900 4150) $PN AD3
J 2
(-5910 4160);
DISPLAY 0.617021 (-5910 4160);
PAINT ORANGE (-5910 4160);
FORCEPROP 2 LASTPIN (-5900 3550) $PN P2
J 2
(-5910 3560);
DISPLAY 0.617021 (-5910 3560);
PAINT ORANGE (-5910 3560);
FORCEPROP 2 LASTPIN (-5900 3300) $PN Y3
J 2
(-5910 3310);
DISPLAY 0.617021 (-5910 3310);
PAINT ORANGE (-5910 3310);
FORCEPROP 2 LASTPIN (-2300 2550) $PN BY47
J 0
(-2290 2560);
DISPLAY 0.617021 (-2290 2560);
PAINT ORANGE (-2290 2560);
FORCEPROP 2 LASTPIN (-2300 3250) $PN BW28
J 0
(-2290 3260);
DISPLAY 0.617021 (-2290 3260);
PAINT ORANGE (-2290 3260);
FORCEPROP 2 LASTPIN (-2300 3300) $PN BV27
J 0
(-2290 3310);
DISPLAY 0.617021 (-2290 3310);
PAINT ORANGE (-2290 3310);
FORCEPROP 2 LASTPIN (-5900 4250) $PN W4
J 2
(-5910 4260);
DISPLAY 0.617021 (-5910 4260);
PAINT ORANGE (-5910 4260);
FORCEPROP 2 LASTPIN (-5900 4200) $PN V3
J 2
(-5910 4210);
DISPLAY 0.617021 (-5910 4210);
PAINT ORANGE (-5910 4210);
FORCEPROP 2 LASTPIN (-5900 3700) $PN R3
J 2
(-5910 3710);
DISPLAY 0.617021 (-5910 3710);
PAINT ORANGE (-5910 3710);
FORCEPROP 2 LASTPIN (-5900 3500) $PN P4
J 2
(-5910 3510);
DISPLAY 0.617021 (-5910 3510);
PAINT ORANGE (-5910 3510);
FORCEPROP 2 LASTPIN (-2300 3000) $PN CA48
J 0
(-2290 3010);
DISPLAY 0.617021 (-2290 3010);
PAINT ORANGE (-2290 3010);
FORCEPROP 2 LASTPIN (-5900 3100) $PN BR17
J 2
(-5910 3110);
DISPLAY 0.617021 (-5910 3110);
PAINT ORANGE (-5910 3110);
FORCEPROP 2 LASTPIN (-5900 2850) $PN BG15
J 2
(-5910 2860);
DISPLAY 0.617021 (-5910 2860);
PAINT ORANGE (-5910 2860);
FORCEPROP 2 LASTPIN (-2300 4000) $PN CA32
J 0
(-2290 4010);
DISPLAY 0.617021 (-2290 4010);
PAINT ORANGE (-2290 4010);
FORCEPROP 2 LASTPIN (-2300 4200) $PN BW39
J 0
(-2290 4210);
DISPLAY 0.617021 (-2290 4210);
PAINT ORANGE (-2290 4210);
FORCEPROP 1 LAST PART_NUMBER H91415-002
J 0
(-5850 1800);
DISPLAY 0.617021 (-5850 1800);
PAINT BLUE (-5850 1800);
FORCEPROP 2 LASTPIN (-5900 2250) $PN BK17
J 2
(-5910 2260);
DISPLAY 0.617021 (-5910 2260);
PAINT ORANGE (-5910 2260);
FORCEPROP 2 LASTPIN (-5900 2300) $PN BG18
J 2
(-5910 2310);
DISPLAY 0.617021 (-5910 2310);
PAINT ORANGE (-5910 2310);
FORCEPROP 2 LASTPIN (-5900 2350) $PN BR13
J 2
(-5910 2360);
DISPLAY 0.617021 (-5910 2360);
PAINT ORANGE (-5910 2360);
FORCEPROP 2 LASTPIN (-5900 2800) $PN BG22
J 2
(-5910 2810);
DISPLAY 0.617021 (-5910 2810);
PAINT ORANGE (-5910 2810);
FORCEPROP 2 LASTPIN (-5900 3450) $PN Y1
J 2
(-5910 3460);
DISPLAY 0.617021 (-5910 3460);
PAINT ORANGE (-5910 3460);
FORCEPROP 2 LASTPIN (-5900 3800) $PN AC2
J 2
(-5910 3810);
DISPLAY 0.617021 (-5910 3810);
PAINT ORANGE (-5910 3810);
FORCEPROP 2 LASTPIN (-5900 3650) $PN AB1
J 2
(-5910 3660);
DISPLAY 0.617021 (-5910 3660);
PAINT ORANGE (-5910 3660);
FORCEPROP 2 LASTPIN (-5900 3850) $PN R1
J 2
(-5910 3860);
DISPLAY 0.617021 (-5910 3860);
PAINT ORANGE (-5910 3860);
FORCEPROP 2 LASTPIN (-5900 3900) $PN T4
J 2
(-5910 3910);
DISPLAY 0.617021 (-5910 3910);
PAINT ORANGE (-5910 3910);
FORCEPROP 2 LASTPIN (-5900 3950) $PN AB3
J 2
(-5910 3960);
DISPLAY 0.617021 (-5910 3960);
PAINT ORANGE (-5910 3960);
FORCEPROP 2 LASTPIN (-2300 2900) $PN CA41
J 0
(-2290 2910);
DISPLAY 0.617021 (-2290 2910);
PAINT ORANGE (-2290 2910);
FORCEPROP 2 LASTPIN (-2300 3350) $PN BY27
J 0
(-2290 3360);
DISPLAY 0.617021 (-2290 3360);
PAINT ORANGE (-2290 3360);
FORCEPROP 2 LASTPIN (-2300 3400) $PN BV29
J 0
(-2290 3410);
DISPLAY 0.617021 (-2290 3410);
PAINT ORANGE (-2290 3410);
FORCEPROP 2 LASTPIN (-2300 3550) $PN CA28
J 0
(-2290 3560);
DISPLAY 0.617021 (-2290 3560);
PAINT ORANGE (-2290 3560);
FORCEPROP 2 LASTPIN (-2300 3750) $PN BV31
J 0
(-2290 3760);
DISPLAY 0.617021 (-2290 3760);
PAINT ORANGE (-2290 3760);
FORCEPROP 2 LASTPIN (-2300 3800) $PN BV33
J 0
(-2290 3810);
DISPLAY 0.617021 (-2290 3810);
PAINT ORANGE (-2290 3810);
FORCEPROP 2 LASTPIN (-2300 3850) $PN CA30
J 0
(-2290 3860);
DISPLAY 0.617021 (-2290 3860);
PAINT ORANGE (-2290 3860);
FORCEPROP 2 LASTPIN (-2300 3650) $PN BW32
J 0
(-2290 3660);
DISPLAY 0.617021 (-2290 3660);
PAINT ORANGE (-2290 3660);
FORCEPROP 2 LASTPIN (-2300 3700) $PN BY29
J 0
(-2290 3710);
DISPLAY 0.617021 (-2290 3710);
PAINT ORANGE (-2290 3710);
FORCEPROP 2 LASTPIN (-2300 4150) $PN BY35
J 0
(-2290 4160);
DISPLAY 0.617021 (-2290 4160);
PAINT ORANGE (-2290 4160);
FORCEPROP 2 LASTPIN (-2300 4250) $PN CA39
J 0
(-2290 4260);
DISPLAY 0.617021 (-2290 4260);
PAINT ORANGE (-2290 4260);
FORCEPROP 2 LASTPIN (-2300 4300) $PN BY33
J 0
(-2290 4310);
DISPLAY 0.617021 (-2290 4310);
PAINT ORANGE (-2290 4310);
FORCEPROP 2 LASTPIN (-2300 4350) $PN CA34
J 0
(-2290 4360);
DISPLAY 0.617021 (-2290 4360);
PAINT ORANGE (-2290 4360);
FORCEPROP 2 LASTPIN (-5900 2700) $PN BH13
J 2
(-5910 2710);
DISPLAY 0.617021 (-5910 2710);
PAINT ORANGE (-5910 2710);
FORCEPROP 2 LASTPIN (-2300 3450) $PN BW30
J 0
(-2290 3460);
DISPLAY 0.617021 (-2290 3460);
PAINT ORANGE (-2290 3460);
FORCEPROP 2 LASTPIN (-2300 3500) $PN BW34
J 0
(-2290 3510);
DISPLAY 0.617021 (-2290 3510);
PAINT ORANGE (-2290 3510);
FORCEPROP 2 LASTPIN (-2300 2750) $PN BW43
J 0
(-2290 2760);
DISPLAY 0.617021 (-2290 2760);
PAINT ORANGE (-2290 2760);
FORCEPROP 2 LASTPIN (-2300 2800) $PN BV42
J 0
(-2290 2810);
DISPLAY 0.617021 (-2290 2810);
PAINT ORANGE (-2290 2810);
FORCEPROP 2 LASTPIN (-2300 4050) $PN BW37
J 0
(-2290 4060);
DISPLAY 0.617021 (-2290 4060);
PAINT ORANGE (-2290 4060);
FORCEPROP 2 LASTPIN (-5900 2400) $PN BN11
J 2
(-5910 2410);
DISPLAY 0.617021 (-5910 2410);
PAINT ORANGE (-5910 2410);
FORCEPROP 2 LASTPIN (-2300 2850) $PN BW48
J 0
(-2290 2860);
DISPLAY 0.617021 (-2290 2860);
PAINT ORANGE (-2290 2860);
FORCEPROP 2 LASTPIN (-5900 2900) $PN BL15
J 2
(-5910 2910);
DISPLAY 0.617021 (-5910 2910);
PAINT ORANGE (-5910 2910);
FORCEPROP 2 LASTPIN (-5900 2550) $PN BK9
J 2
(-5910 2560);
DISPLAY 0.617021 (-5910 2560);
PAINT ORANGE (-5910 2560);
FORCEPROP 2 LASTPIN (-5900 2450) $PN BH20
J 2
(-5910 2460);
DISPLAY 0.617021 (-5910 2460);
PAINT ORANGE (-5910 2460);
FORCEPROP 2 LASTPIN (-5900 2750) $PN BK13
J 2
(-5910 2760);
DISPLAY 0.617021 (-5910 2760);
PAINT ORANGE (-5910 2760);
FORCEPROP 2 LASTPIN (-5900 3150) $PN BM20
J 2
(-5910 3160);
DISPLAY 0.617021 (-5910 3160);
PAINT ORANGE (-5910 3160);
FORCEPROP 2 LASTPIN (-5900 2500) $PN BL11
J 2
(-5910 2510);
DISPLAY 0.617021 (-5910 2510);
PAINT ORANGE (-5910 2510);
FORCEPROP 2 LASTPIN (-5900 3050) $PN BH17
J 2
(-5910 3060);
DISPLAY 0.617021 (-5910 3060);
PAINT ORANGE (-5910 3060);
FORCEPROP 2 LASTPIN (-5900 3000) $PN BJ22
J 2
(-5910 3010);
DISPLAY 0.617021 (-5910 3010);
PAINT ORANGE (-5910 3010);
FORCEPROP 2 LASTPIN (-5900 2950) $PN BK20
J 2
(-5910 2960);
DISPLAY 0.617021 (-5910 2960);
PAINT ORANGE (-5910 2960);
FORCEPROP 2 LASTPIN (-5900 2650) $PN BN18
J 2
(-5910 2660);
DISPLAY 0.617021 (-5910 2660);
PAINT ORANGE (-5910 2660);
FORCEPROP 2 LASTPIN (-5900 2600) $PN BL18
J 2
(-5910 2610);
DISPLAY 0.617021 (-5910 2610);
PAINT ORANGE (-5910 2610);
FORCEPROP 1 LAST LOCATION U7C1
J 0
(-5850 4675);
DISPLAY 0.617021 (-5850 4675);
PAINT AQUA (-5850 4675);
FORCEPROP 1 LAST MATERIAL IC
J 0
(-5850 4600);
DISPLAY 0.617021 (-5850 4600);
PAINT SKYBLUE (-5850 4600);
FORCEPROP 2 LASTPIN (-2300 2500) $PN BV47
J 0
(-2290 2510);
DISPLAY 0.617021 (-2290 2510);
PAINT ORANGE (-2290 2510);
FORCEPROP 2 LASTPIN (-2300 2650) $PN BY44
J 0
(-2290 2660);
DISPLAY 0.617021 (-2290 2660);
PAINT ORANGE (-2290 2660);
FORCEPROP 2 LASTPIN (-2300 3050) $PN BV44
J 0
(-2290 3060);
DISPLAY 0.617021 (-2290 3060);
PAINT ORANGE (-2290 3060);
FORCEPROP 2 LASTPIN (-2300 3100) $PN BR46
J 0
(-2290 3110);
DISPLAY 0.617021 (-2290 3110);
PAINT ORANGE (-2290 3110);
FORCEPROP 2 LASTPIN (-2300 2700) $PN BL44
J 0
(-2290 2710);
DISPLAY 0.617021 (-2290 2710);
PAINT ORANGE (-2290 2710);
FORCEPROP 2 LASTPIN (-2300 2600) $PN BN40
J 0
(-2290 2610);
DISPLAY 0.617021 (-2290 2610);
PAINT ORANGE (-2290 2610);
FORCEPROP 2 LASTPIN (-2300 2100) $PN BJ44
J 0
(-2290 2110);
DISPLAY 0.617021 (-2290 2110);
PAINT ORANGE (-2290 2110);
FORCEPROP 2 LASTPIN (-2300 2050) $PN BK46
J 0
(-2290 2060);
DISPLAY 0.617021 (-2290 2060);
PAINT ORANGE (-2290 2060);
FORCEPROP 2 LASTPIN (-2300 2000) $PN BR42
J 0
(-2290 2010);
DISPLAY 0.617021 (-2290 2010);
PAINT ORANGE (-2290 2010);
FORCEPROP 2 LASTPIN (-2300 2150) $PN BW45
J 0
(-2290 2160);
DISPLAY 0.617021 (-2290 2160);
PAINT ORANGE (-2290 2160);
FORCEPROP 2 LASTPIN (-2300 2200) $PN BM42
J 0
(-2290 2210);
DISPLAY 0.617021 (-2290 2210);
PAINT ORANGE (-2290 2210);
FORCEPROP 2 LASTPIN (-2300 2250) $PN BM38
J 0
(-2290 2260);
DISPLAY 0.617021 (-2290 2260);
PAINT ORANGE (-2290 2260);
FORCEPROP 2 LASTPIN (-2300 2300) $PN BW41
J 0
(-2290 2310);
DISPLAY 0.617021 (-2290 2310);
PAINT ORANGE (-2290 2310);
FORCEPROP 2 LASTPIN (-2300 2350) $PN CA45
J 0
(-2290 2360);
DISPLAY 0.617021 (-2290 2360);
PAINT ORANGE (-2290 2360);
FORCEPROP 2 LASTPIN (-2300 2400) $PN BR38
J 0
(-2290 2410);
DISPLAY 0.617021 (-2290 2410);
PAINT ORANGE (-2290 2410);
FORCEPROP 2 LASTPIN (-2300 2450) $PN BY42
J 0
(-2290 2460);
DISPLAY 0.617021 (-2290 2460);
PAINT ORANGE (-2290 2460);
FORCEPROP 2 LAST CDS_LIB mstr_u_proc
J 0
(-4100 3200);
PAINT ORANGE (-4100 3200);
DISPLAY INVISIBLE (-4100 3200);
FORCEPROP 2 LAST SEC 6
J 0
(-5550 4725);
DISPLAY 0.680851 (-5550 4725);
PAINT MONO (-5550 4725);
DISPLAY INVISIBLE (-5550 4725);
FORCEPROP 2 LAST CDS_LOCATION U7C1
J 0
(-5550 4675);
DISPLAY 0.617021 (-5550 4675);
PAINT AQUA (-5550 4675);
DISPLAY INVISIBLE (-5550 4675);
FORCEPROP 1 LAST PACK_TYPE BGA1
J 0
(-5850 4700);
PAINT SKYBLUE (-5850 4700);
DISPLAY INVISIBLE (-5850 4700);
FORCEPROP 2 LAST SEC_TYPE BGA1
J 0
(-5550 4725);
DISPLAY 1.021277 (-5550 4725);
PAINT ORANGE (-5550 4725);
DISPLAY INVISIBLE (-5550 4725);
FORCEPROP 0 LAST BOM_COST SB
J 0
(-5600 5375);
DISPLAY 1.361702 (-5600 5375);
PAINT ORANGE (-5600 5375);
DISPLAY INVISIBLE (-5600 5375);
FORCEPROP 0 LAST ROOM SB
J 0
(-5600 5275);
DISPLAY 1.361702 (-5600 5275);
PAINT ORANGE (-5600 5275);
DISPLAY INVISIBLE (-5600 5275);
FORCEPROP 1 LAST PATH I115
J 0
(-4100 4600);
PAINT GREEN (-4100 4600);
DISPLAY INVISIBLE (-4100 4600);
FORCEADD OFFPAGE..2
(-775 2950);
FORCEPROP 2 LAST $XR0 190 
J 0
(-586 2950);
DISPLAY 0.638298 (-586 2950);
PAINT MONO (-586 2950);
FORCEPROP 1 LAST COMMENT_BODY TRUE
J 0
(-820 2855);
DISPLAY 0.872340 (-820 2855);
PAINT GREEN (-820 2855);
DISPLAY INVISIBLE (-820 2855);
FORCEPROP 1 LAST OFFPAGE TRUE
J 0
(-450 2825);
DISPLAY 0.872340 (-450 2825);
PAINT GREEN (-450 2825);
DISPLAY INVISIBLE (-450 2825);
FORCEPROP 2 LAST PATH I119
J 0
(-600 3025);
DISPLAY 1.021277 (-600 3025);
PAINT ORANGE (-600 3025);
DISPLAY INVISIBLE (-600 3025);
FORCEPROP 2 LAST CDS_LIB mstr_standard
J 0
(-775 2950);
PAINT ORANGE (-775 2950);
DISPLAY INVISIBLE (-775 2950);
FORCEADD TAP..6
(-6975 3300);
FORCEPROP 1 LASTPIN (-6925 3300) BN 0
J 0
(-6977 3308);
DISPLAY 0.617021 (-6977 3308);
PAINT GREEN (-6977 3308);
FORCEPROP 1 LAST HDL_TAP TRUE
J 0
(-6650 3175);
DISPLAY 0.872340 (-6650 3175);
PAINT ORANGE (-6650 3175);
DISPLAY INVISIBLE (-6650 3175);
FORCEPROP 1 LAST BODY_TYPE PLUMBING
J 0
(-6975 3250);
DISPLAY 0.872340 (-6975 3250);
PAINT GREEN (-6975 3250);
DISPLAY INVISIBLE (-6975 3250);
FORCEPROP 1 LAST PATH I120
J 0
(-6977 3300);
DISPLAY 0.872340 (-6977 3300);
PAINT GREEN (-6977 3300);
DISPLAY INVISIBLE (-6977 3300);
FORCEPROP 2 LAST CDS_LIB mstr_standard
J 0
(-6975 3300);
PAINT ORANGE (-6975 3300);
DISPLAY INVISIBLE (-6975 3300);
FORCEADD TAP..6
(-6975 3350);
FORCEPROP 1 LASTPIN (-6925 3350) BN 1
J 0
(-6977 3358);
DISPLAY 0.617021 (-6977 3358);
PAINT GREEN (-6977 3358);
FORCEPROP 1 LAST HDL_TAP TRUE
J 0
(-6650 3225);
DISPLAY 0.872340 (-6650 3225);
PAINT ORANGE (-6650 3225);
DISPLAY INVISIBLE (-6650 3225);
FORCEPROP 1 LAST BODY_TYPE PLUMBING
J 0
(-6975 3300);
DISPLAY 0.872340 (-6975 3300);
PAINT GREEN (-6975 3300);
DISPLAY INVISIBLE (-6975 3300);
FORCEPROP 2 LAST CDS_LIB mstr_standard
J 0
(-6975 3350);
PAINT ORANGE (-6975 3350);
DISPLAY INVISIBLE (-6975 3350);
FORCEPROP 1 LAST PATH I121
J 0
(-6977 3350);
DISPLAY 0.872340 (-6977 3350);
PAINT GREEN (-6977 3350);
DISPLAY INVISIBLE (-6977 3350);
FORCEADD TAP..6
(-6975 3400);
FORCEPROP 1 LASTPIN (-6925 3400) BN 2
J 0
(-6977 3408);
DISPLAY 0.617021 (-6977 3408);
PAINT GREEN (-6977 3408);
FORCEPROP 1 LAST HDL_TAP TRUE
J 0
(-6650 3275);
DISPLAY 0.872340 (-6650 3275);
PAINT ORANGE (-6650 3275);
DISPLAY INVISIBLE (-6650 3275);
FORCEPROP 1 LAST BODY_TYPE PLUMBING
J 0
(-6975 3350);
DISPLAY 0.872340 (-6975 3350);
PAINT GREEN (-6975 3350);
DISPLAY INVISIBLE (-6975 3350);
FORCEPROP 2 LAST CDS_LIB mstr_standard
J 0
(-6975 3400);
PAINT ORANGE (-6975 3400);
DISPLAY INVISIBLE (-6975 3400);
FORCEPROP 1 LAST PATH I122
J 0
(-6977 3400);
DISPLAY 0.872340 (-6977 3400);
PAINT GREEN (-6977 3400);
DISPLAY INVISIBLE (-6977 3400);
FORCEADD TAP..6
(-6975 3450);
FORCEPROP 1 LASTPIN (-6925 3450) BN 3
J 0
(-6977 3458);
DISPLAY 0.617021 (-6977 3458);
PAINT GREEN (-6977 3458);
FORCEPROP 1 LAST HDL_TAP TRUE
J 0
(-6650 3325);
DISPLAY 0.872340 (-6650 3325);
PAINT ORANGE (-6650 3325);
DISPLAY INVISIBLE (-6650 3325);
FORCEPROP 1 LAST BODY_TYPE PLUMBING
J 0
(-6975 3400);
DISPLAY 0.872340 (-6975 3400);
PAINT GREEN (-6975 3400);
DISPLAY INVISIBLE (-6975 3400);
FORCEPROP 1 LAST PATH I123
J 0
(-6977 3450);
DISPLAY 0.872340 (-6977 3450);
PAINT GREEN (-6977 3450);
DISPLAY INVISIBLE (-6977 3450);
FORCEPROP 2 LAST CDS_LIB mstr_standard
J 0
(-6975 3450);
PAINT ORANGE (-6975 3450);
DISPLAY INVISIBLE (-6975 3450);
FORCEADD OFFPAGE..6
(-7550 3475);
FORCEPROP 2 LAST $XR0 146 
J 0
(-7860 3475);
DISPLAY 0.638298 (-7860 3475);
PAINT MONO (-7860 3475);
FORCEPROP 2 LAST CDS_LIB mstr_standard
J 0
(-7550 3475);
PAINT ORANGE (-7550 3475);
DISPLAY INVISIBLE (-7550 3475);
FORCEPROP 2 LAST PATH I124
J 0
(-7500 3550);
DISPLAY 1.021277 (-7500 3550);
PAINT ORANGE (-7500 3550);
DISPLAY INVISIBLE (-7500 3550);
FORCEPROP 1 LAST OFFPAGE TRUE
J 0
(-7225 3350);
DISPLAY 0.872340 (-7225 3350);
PAINT GREEN (-7225 3350);
DISPLAY INVISIBLE (-7225 3350);
FORCEPROP 1 LAST COMMENT_BODY TRUE
J 0
(-7450 3400);
DISPLAY 0.872340 (-7450 3400);
PAINT GREEN (-7450 3400);
DISPLAY INVISIBLE (-7450 3400);
FORCEADD OFFPAGE..1
(-7550 4400);
FORCEPROP 2 LAST $XR3 182 
J 0
(-7922 4364);
DISPLAY 0.638298 (-7922 4364);
PAINT MONO (-7922 4364);
FORCEPROP 2 LAST $XR2 146 
J 0
(-7802 4364);
DISPLAY 0.638298 (-7802 4364);
PAINT MONO (-7802 4364);
FORCEPROP 2 LAST $XR1 133 
J 0
(-7922 4400);
DISPLAY 0.638298 (-7922 4400);
PAINT MONO (-7922 4400);
FORCEPROP 2 LAST $XR0 120 
J 0
(-7802 4400);
DISPLAY 0.638298 (-7802 4400);
PAINT MONO (-7802 4400);
FORCEPROP 2 LAST CDS_LIB mstr_standard
J 0
(-7550 4400);
PAINT ORANGE (-7550 4400);
DISPLAY INVISIBLE (-7550 4400);
FORCEPROP 2 LAST PATH I125
J 0
(-7500 4475);
DISPLAY 1.021277 (-7500 4475);
PAINT ORANGE (-7500 4475);
DISPLAY INVISIBLE (-7500 4475);
FORCEPROP 1 LAST OFFPAGE TRUE
J 0
(-7225 4275);
DISPLAY 0.872340 (-7225 4275);
PAINT GREEN (-7225 4275);
DISPLAY INVISIBLE (-7225 4275);
FORCEPROP 1 LAST COMMENT_BODY TRUE
J 0
(-7425 4300);
DISPLAY 0.872340 (-7425 4300);
PAINT GREEN (-7425 4300);
DISPLAY INVISIBLE (-7425 4300);
FORCEADD OFFPAGE..4
R 2
(-7550 3950);
FORCEPROP 2 LAST $XR1 164 
J 0
(-7922 3950);
DISPLAY 0.638298 (-7922 3950);
PAINT MONO (-7922 3950);
FORCEPROP 2 LAST $XR0 181 
J 0
(-7802 3950);
DISPLAY 0.638298 (-7802 3950);
PAINT MONO (-7802 3950);
FORCEPROP 2 LAST CDS_LIB mstr_standard
J 0
(-7550 3950);
PAINT ORANGE (-7550 3950);
DISPLAY INVISIBLE (-7550 3950);
FORCEPROP 2 LAST PATH I127
J 0
(-7500 4025);
DISPLAY 1.021277 (-7500 4025);
PAINT ORANGE (-7500 4025);
DISPLAY INVISIBLE (-7500 4025);
FORCEPROP 1 LAST OFFPAGE TRUE
J 2
(-7875 3825);
DISPLAY 0.872340 (-7875 3825);
PAINT GREEN (-7875 3825);
DISPLAY INVISIBLE (-7875 3825);
FORCEPROP 1 LAST COMMENT_BODY TRUE
J 2
(-7525 3850);
DISPLAY 0.872340 (-7525 3850);
PAINT GREEN (-7525 3850);
DISPLAY INVISIBLE (-7525 3850);
FORCEADD OFFPAGE..4
R 2
(-7550 4000);
FORCEPROP 2 LAST $XR1 164 
J 0
(-7922 4000);
DISPLAY 0.638298 (-7922 4000);
PAINT MONO (-7922 4000);
FORCEPROP 2 LAST $XR0 181 
J 0
(-7802 4000);
DISPLAY 0.638298 (-7802 4000);
PAINT MONO (-7802 4000);
FORCEPROP 2 LAST CDS_LIB mstr_standard
J 0
(-7550 4000);
PAINT ORANGE (-7550 4000);
DISPLAY INVISIBLE (-7550 4000);
FORCEPROP 2 LAST PATH I128
J 0
(-7500 4075);
DISPLAY 1.021277 (-7500 4075);
PAINT ORANGE (-7500 4075);
DISPLAY INVISIBLE (-7500 4075);
FORCEPROP 1 LAST OFFPAGE TRUE
J 2
(-7875 3875);
DISPLAY 0.872340 (-7875 3875);
PAINT GREEN (-7875 3875);
DISPLAY INVISIBLE (-7875 3875);
FORCEPROP 1 LAST COMMENT_BODY TRUE
J 2
(-7525 3900);
DISPLAY 0.872340 (-7525 3900);
PAINT GREEN (-7525 3900);
DISPLAY INVISIBLE (-7525 3900);
FORCEADD OFFPAGE..4
R 2
(-7550 3900);
FORCEPROP 2 LAST $XR1 164 
J 0
(-7922 3900);
DISPLAY 0.638298 (-7922 3900);
PAINT MONO (-7922 3900);
FORCEPROP 2 LAST $XR0 181 
J 0
(-7802 3900);
DISPLAY 0.638298 (-7802 3900);
PAINT MONO (-7802 3900);
FORCEPROP 2 LAST CDS_LIB mstr_standard
J 0
(-7550 3900);
PAINT ORANGE (-7550 3900);
DISPLAY INVISIBLE (-7550 3900);
FORCEPROP 2 LAST PATH I129
J 0
(-7500 3975);
DISPLAY 1.021277 (-7500 3975);
PAINT ORANGE (-7500 3975);
DISPLAY INVISIBLE (-7500 3975);
FORCEPROP 1 LAST OFFPAGE TRUE
J 2
(-7875 3775);
DISPLAY 0.872340 (-7875 3775);
PAINT GREEN (-7875 3775);
DISPLAY INVISIBLE (-7875 3775);
FORCEPROP 1 LAST COMMENT_BODY TRUE
J 2
(-7525 3800);
DISPLAY 0.872340 (-7525 3800);
PAINT GREEN (-7525 3800);
DISPLAY INVISIBLE (-7525 3800);
FORCEADD OFFPAGE..4
R 2
(-7550 3800);
FORCEPROP 2 LAST CDS_LIB mstr_standard
J 0
(-7550 3800);
PAINT ORANGE (-7550 3800);
DISPLAY INVISIBLE (-7550 3800);
FORCEPROP 2 LAST PATH I13
J 0
(-7500 3875);
DISPLAY 1.021277 (-7500 3875);
PAINT ORANGE (-7500 3875);
DISPLAY INVISIBLE (-7500 3875);
FORCEPROP 1 LAST OFFPAGE TRUE
J 2
(-7875 3675);
DISPLAY 0.872340 (-7875 3675);
PAINT GREEN (-7875 3675);
DISPLAY INVISIBLE (-7875 3675);
FORCEPROP 1 LAST COMMENT_BODY TRUE
J 2
(-7525 3700);
DISPLAY 0.872340 (-7525 3700);
PAINT GREEN (-7525 3700);
DISPLAY INVISIBLE (-7525 3700);
FORCEPROP 2 LAST $XR0 133 
J 0
(-7976 3800);
DISPLAY 0.638298 (-7976 3800);
PAINT MONO (-7976 3800);
DISPLAY INVISIBLE (-7976 3800);
FORCEADD OFFPAGE..5
(-7750 2550);
FORCEPROP 1 LAST COMMENT_BODY TRUE
J 0
(-7650 2475);
DISPLAY 1.404255 (-7650 2475);
PAINT PEACH (-7650 2475);
DISPLAY INVISIBLE (-7650 2475);
FORCEPROP 1 LAST OFFPAGE TRUE
J 0
(-7425 2425);
PAINT GREEN (-7425 2425);
DISPLAY INVISIBLE (-7425 2425);
FORCEPROP 2 LAST PATH I130
J 0
(-7700 2625);
DISPLAY 1.021277 (-7700 2625);
PAINT ORANGE (-7700 2625);
DISPLAY INVISIBLE (-7700 2625);
FORCEPROP 2 LAST CDS_LIB mstr_standard
J 0
(-7750 2550);
PAINT ORANGE (-7750 2550);
DISPLAY INVISIBLE (-7750 2550);
FORCEPROP 2 LAST $XR2 170 
J 0
(-8179 2550);
DISPLAY 0.638298 (-8179 2550);
PAINT MONO (-8179 2550);
DISPLAY INVISIBLE (-8179 2550);
FORCEPROP 2 LAST $XR1 145 
J 0
(-8179 2550);
DISPLAY 0.638298 (-8179 2550);
PAINT MONO (-8179 2550);
DISPLAY INVISIBLE (-8179 2550);
FORCEPROP 2 LAST $XR0 119 
J 0
(-8179 2550);
DISPLAY 0.638298 (-8179 2550);
PAINT MONO (-8179 2550);
DISPLAY INVISIBLE (-8179 2550);
FORCEADD OFFPAGE..4
R 2
(-7175 2250);
FORCEPROP 2 LAST $XR2 146 
J 0
(-7637 2250);
DISPLAY 0.638298 (-7637 2250);
PAINT MONO (-7637 2250);
FORCEPROP 2 LAST $XR1 94 
J 0
(-7517 2250);
DISPLAY 0.638298 (-7517 2250);
PAINT MONO (-7517 2250);
FORCEPROP 2 LAST $XR0 218 
J 0
(-7427 2250);
DISPLAY 0.638298 (-7427 2250);
PAINT MONO (-7427 2250);
FORCEPROP 1 LAST COMMENT_BODY TRUE
J 2
(-7150 2150);
DISPLAY 0.872340 (-7150 2150);
PAINT GREEN (-7150 2150);
DISPLAY INVISIBLE (-7150 2150);
FORCEPROP 1 LAST OFFPAGE TRUE
J 2
(-7500 2125);
DISPLAY 0.872340 (-7500 2125);
PAINT GREEN (-7500 2125);
DISPLAY INVISIBLE (-7500 2125);
FORCEPROP 2 LAST PATH I131
J 0
(-7125 2325);
DISPLAY 1.021277 (-7125 2325);
PAINT ORANGE (-7125 2325);
DISPLAY INVISIBLE (-7125 2325);
FORCEPROP 2 LAST CDS_LIB mstr_standard
J 0
(-7175 2250);
PAINT ORANGE (-7175 2250);
DISPLAY INVISIBLE (-7175 2250);
FORCEADD OFFPAGE..4
R 2
(-7175 2200);
FORCEPROP 2 LAST $XR2 145 
J 0
(-7637 2200);
DISPLAY 0.638298 (-7637 2200);
PAINT MONO (-7637 2200);
FORCEPROP 2 LAST $XR1 94 
J 0
(-7517 2200);
DISPLAY 0.638298 (-7517 2200);
PAINT MONO (-7517 2200);
FORCEPROP 2 LAST $XR0 215 
J 0
(-7427 2200);
DISPLAY 0.638298 (-7427 2200);
PAINT MONO (-7427 2200);
FORCEPROP 1 LAST COMMENT_BODY TRUE
J 2
(-7150 2100);
DISPLAY 0.872340 (-7150 2100);
PAINT GREEN (-7150 2100);
DISPLAY INVISIBLE (-7150 2100);
FORCEPROP 1 LAST OFFPAGE TRUE
J 2
(-7500 2075);
DISPLAY 0.872340 (-7500 2075);
PAINT GREEN (-7500 2075);
DISPLAY INVISIBLE (-7500 2075);
FORCEPROP 2 LAST PATH I132
J 0
(-7125 2275);
DISPLAY 1.021277 (-7125 2275);
PAINT ORANGE (-7125 2275);
DISPLAY INVISIBLE (-7125 2275);
FORCEPROP 2 LAST CDS_LIB mstr_standard
J 0
(-7175 2200);
PAINT ORANGE (-7175 2200);
DISPLAY INVISIBLE (-7175 2200);
FORCEADD OFFPAGE..1
(-7175 2350);
FORCEPROP 2 LAST $XR2 145 
J 0
(-7637 2350);
DISPLAY 0.638298 (-7637 2350);
PAINT MONO (-7637 2350);
FORCEPROP 2 LAST $XR1 94 
J 0
(-7517 2350);
DISPLAY 0.638298 (-7517 2350);
PAINT MONO (-7517 2350);
FORCEPROP 2 LAST $XR0 226 
J 0
(-7427 2350);
DISPLAY 0.638298 (-7427 2350);
PAINT MONO (-7427 2350);
FORCEPROP 1 LAST COMMENT_BODY TRUE
J 0
(-7050 2250);
DISPLAY 0.872340 (-7050 2250);
PAINT GREEN (-7050 2250);
DISPLAY INVISIBLE (-7050 2250);
FORCEPROP 1 LAST OFFPAGE TRUE
J 0
(-6850 2225);
DISPLAY 0.872340 (-6850 2225);
PAINT GREEN (-6850 2225);
DISPLAY INVISIBLE (-6850 2225);
FORCEPROP 2 LAST PATH I136
J 0
(-7125 2425);
DISPLAY 1.021277 (-7125 2425);
PAINT ORANGE (-7125 2425);
DISPLAY INVISIBLE (-7125 2425);
FORCEPROP 2 LAST CDS_LIB mstr_standard
J 0
(-7175 2350);
PAINT ORANGE (-7175 2350);
DISPLAY INVISIBLE (-7175 2350);
FORCEADD OFFPAGE..4
R 2
(-7175 2300);
FORCEPROP 2 LAST $XR2 144 
J 0
(-7637 2300);
DISPLAY 0.638298 (-7637 2300);
PAINT MONO (-7637 2300);
FORCEPROP 2 LAST $XR1 94 
J 0
(-7517 2300);
DISPLAY 0.638298 (-7517 2300);
PAINT MONO (-7517 2300);
FORCEPROP 2 LAST $XR0 223 
J 0
(-7427 2300);
DISPLAY 0.638298 (-7427 2300);
PAINT MONO (-7427 2300);
FORCEPROP 1 LAST COMMENT_BODY TRUE
J 2
(-7150 2200);
DISPLAY 0.872340 (-7150 2200);
PAINT GREEN (-7150 2200);
DISPLAY INVISIBLE (-7150 2200);
FORCEPROP 1 LAST OFFPAGE TRUE
J 2
(-7500 2175);
DISPLAY 0.872340 (-7500 2175);
PAINT GREEN (-7500 2175);
DISPLAY INVISIBLE (-7500 2175);
FORCEPROP 2 LAST PATH I137
J 0
(-7125 2375);
DISPLAY 1.021277 (-7125 2375);
PAINT ORANGE (-7125 2375);
DISPLAY INVISIBLE (-7125 2375);
FORCEPROP 2 LAST CDS_LIB mstr_standard
J 0
(-7175 2300);
PAINT ORANGE (-7175 2300);
DISPLAY INVISIBLE (-7175 2300);
FORCEADD OFFPAGE..5
(-7175 2950);
FORCEPROP 2 LAST $XR0 147 
J 0
(-7460 2950);
DISPLAY 0.638298 (-7460 2950);
PAINT MONO (-7460 2950);
FORCEPROP 1 LAST COMMENT_BODY TRUE
J 0
(-7075 2875);
DISPLAY 1.404255 (-7075 2875);
PAINT PEACH (-7075 2875);
DISPLAY INVISIBLE (-7075 2875);
FORCEPROP 1 LAST OFFPAGE TRUE
J 0
(-6850 2825);
PAINT GREEN (-6850 2825);
DISPLAY INVISIBLE (-6850 2825);
FORCEPROP 2 LAST PATH I139
J 0
(-7125 3025);
DISPLAY 1.021277 (-7125 3025);
PAINT ORANGE (-7125 3025);
DISPLAY INVISIBLE (-7125 3025);
FORCEPROP 2 LAST CDS_LIB mstr_standard
J 0
(-7175 2950);
PAINT ORANGE (-7175 2950);
DISPLAY INVISIBLE (-7175 2950);
FORCEADD OFFPAGE..4
R 2
(-7550 3850);
FORCEPROP 2 LAST $XR0 133 
J 0
(-7802 3850);
DISPLAY 0.638298 (-7802 3850);
PAINT MONO (-7802 3850);
FORCEPROP 2 LAST CDS_LIB mstr_standard
J 0
(-7550 3850);
PAINT ORANGE (-7550 3850);
DISPLAY INVISIBLE (-7550 3850);
FORCEPROP 2 LAST PATH I14
J 0
(-7500 3925);
DISPLAY 1.021277 (-7500 3925);
PAINT ORANGE (-7500 3925);
DISPLAY INVISIBLE (-7500 3925);
FORCEPROP 1 LAST OFFPAGE TRUE
J 2
(-7875 3725);
DISPLAY 0.872340 (-7875 3725);
PAINT GREEN (-7875 3725);
DISPLAY INVISIBLE (-7875 3725);
FORCEPROP 1 LAST COMMENT_BODY TRUE
J 2
(-7525 3750);
DISPLAY 0.872340 (-7525 3750);
PAINT GREEN (-7525 3750);
DISPLAY INVISIBLE (-7525 3750);
FORCEADD OFFPAGE..5
(-7175 3050);
FORCEPROP 2 LAST $XR1 170 
J 0
(-7580 3050);
DISPLAY 0.638298 (-7580 3050);
PAINT MONO (-7580 3050);
FORCEPROP 2 LAST $XR0 147 
J 0
(-7460 3050);
DISPLAY 0.638298 (-7460 3050);
PAINT MONO (-7460 3050);
FORCEPROP 1 LAST COMMENT_BODY TRUE
J 0
(-7075 2975);
DISPLAY 1.404255 (-7075 2975);
PAINT PEACH (-7075 2975);
DISPLAY INVISIBLE (-7075 2975);
FORCEPROP 1 LAST OFFPAGE TRUE
J 0
(-6850 2925);
PAINT GREEN (-6850 2925);
DISPLAY INVISIBLE (-6850 2925);
FORCEPROP 2 LAST PATH I140
J 0
(-7125 3125);
DISPLAY 1.021277 (-7125 3125);
PAINT ORANGE (-7125 3125);
DISPLAY INVISIBLE (-7125 3125);
FORCEPROP 2 LAST CDS_LIB mstr_standard
J 0
(-7175 3050);
PAINT ORANGE (-7175 3050);
DISPLAY INVISIBLE (-7175 3050);
FORCEADD OFFPAGE..4
(-775 3800);
FORCEPROP 2 LAST $XR1 145 
J 0
(-469 3800);
DISPLAY 0.638298 (-469 3800);
PAINT MONO (-469 3800);
FORCEPROP 2 LAST $XR0 164 
J 0
(-589 3800);
DISPLAY 0.638298 (-589 3800);
PAINT MONO (-589 3800);
FORCEPROP 1 LAST COMMENT_BODY TRUE
J 0
(-800 3700);
DISPLAY 1.404255 (-800 3700);
PAINT PEACH (-800 3700);
DISPLAY INVISIBLE (-800 3700);
FORCEPROP 1 LAST OFFPAGE TRUE
J 0
(-450 3675);
PAINT GREEN (-450 3675);
DISPLAY INVISIBLE (-450 3675);
FORCEPROP 2 LAST PATH I141
J 0
(-600 3875);
DISPLAY 1.021277 (-600 3875);
PAINT ORANGE (-600 3875);
DISPLAY INVISIBLE (-600 3875);
FORCEPROP 2 LAST CDS_LIB mstr_standard
J 0
(-775 3800);
PAINT MONO (-775 3800);
DISPLAY INVISIBLE (-775 3800);
FORCEADD OFFPAGE..2
(-400 4200);
FORCEPROP 2 LAST $XR1 147 
J 0
(-211 4164);
DISPLAY 0.638298 (-211 4164);
PAINT MONO (-211 4164);
FORCEPROP 2 LAST $XR0 182 
J 0
(-211 4200);
DISPLAY 0.638298 (-211 4200);
PAINT MONO (-211 4200);
FORCEPROP 1 LAST COMMENT_BODY TRUE
J 0
(-445 4105);
DISPLAY 1.404255 (-445 4105);
PAINT PEACH (-445 4105);
DISPLAY INVISIBLE (-445 4105);
FORCEPROP 1 LAST OFFPAGE TRUE
J 0
(-75 4075);
PAINT GREEN (-75 4075);
DISPLAY INVISIBLE (-75 4075);
FORCEPROP 2 LAST PATH I142
J 0
(-225 4275);
DISPLAY 1.021277 (-225 4275);
PAINT ORANGE (-225 4275);
DISPLAY INVISIBLE (-225 4275);
FORCEPROP 2 LAST CDS_LIB mstr_standard
J 0
(-400 4200);
PAINT MONO (-400 4200);
DISPLAY INVISIBLE (-400 4200);
FORCEADD OFFPAGE..4
(-775 4300);
FORCEPROP 2 LAST $XR2 146 
J 0
(-349 4300);
DISPLAY 0.638298 (-349 4300);
PAINT MONO (-349 4300);
FORCEPROP 2 LAST $XR1 133 
J 0
(-469 4300);
DISPLAY 0.638298 (-469 4300);
PAINT MONO (-469 4300);
FORCEPROP 2 LAST $XR0 119 
J 0
(-589 4300);
DISPLAY 0.638298 (-589 4300);
PAINT MONO (-589 4300);
FORCEPROP 1 LAST COMMENT_BODY TRUE
J 0
(-800 4200);
DISPLAY 1.404255 (-800 4200);
PAINT PEACH (-800 4200);
DISPLAY INVISIBLE (-800 4200);
FORCEPROP 1 LAST OFFPAGE TRUE
J 0
(-450 4175);
PAINT GREEN (-450 4175);
DISPLAY INVISIBLE (-450 4175);
FORCEPROP 2 LAST PATH I143
J 0
(-600 4375);
DISPLAY 1.021277 (-600 4375);
PAINT ORANGE (-600 4375);
DISPLAY INVISIBLE (-600 4375);
FORCEPROP 2 LAST CDS_LIB mstr_standard
J 0
(-775 4300);
PAINT MONO (-775 4300);
DISPLAY INVISIBLE (-775 4300);
FORCEADD OFFPAGE..4
(-775 2100);
FORCEPROP 2 LAST $XR2 146 
J 0
(-349 2100);
DISPLAY 0.638298 (-349 2100);
PAINT MONO (-349 2100);
FORCEPROP 2 LAST $XR1 199 
J 0
(-469 2100);
DISPLAY 0.638298 (-469 2100);
PAINT MONO (-469 2100);
FORCEPROP 2 LAST $XR0 133 
J 0
(-589 2100);
DISPLAY 0.638298 (-589 2100);
PAINT MONO (-589 2100);
FORCEPROP 1 LAST COMMENT_BODY TRUE
J 0
(-800 2000);
DISPLAY 1.404255 (-800 2000);
PAINT PEACH (-800 2000);
DISPLAY INVISIBLE (-800 2000);
FORCEPROP 1 LAST OFFPAGE TRUE
J 0
(-450 1975);
PAINT GREEN (-450 1975);
DISPLAY INVISIBLE (-450 1975);
FORCEPROP 2 LAST PATH I144
J 0
(-600 2175);
DISPLAY 1.021277 (-600 2175);
PAINT ORANGE (-600 2175);
DISPLAY INVISIBLE (-600 2175);
FORCEPROP 2 LAST CDS_LIB mstr_standard
J 0
(-775 2100);
PAINT MONO (-775 2100);
DISPLAY INVISIBLE (-775 2100);
FORCEADD OFFPAGE..4
(-775 2150);
FORCEPROP 2 LAST $XR3 145 
J 0
(-229 2150);
DISPLAY 0.638298 (-229 2150);
PAINT MONO (-229 2150);
FORCEPROP 2 LAST $XR2 186 
J 0
(-349 2150);
DISPLAY 0.638298 (-349 2150);
PAINT MONO (-349 2150);
FORCEPROP 2 LAST $XR1 185 
J 0
(-469 2150);
DISPLAY 0.638298 (-469 2150);
PAINT MONO (-469 2150);
FORCEPROP 2 LAST $XR0 157 
J 0
(-589 2150);
DISPLAY 0.638298 (-589 2150);
PAINT MONO (-589 2150);
FORCEPROP 1 LAST COMMENT_BODY TRUE
J 0
(-800 2050);
DISPLAY 1.404255 (-800 2050);
PAINT PEACH (-800 2050);
DISPLAY INVISIBLE (-800 2050);
FORCEPROP 1 LAST OFFPAGE TRUE
J 0
(-450 2025);
PAINT GREEN (-450 2025);
DISPLAY INVISIBLE (-450 2025);
FORCEPROP 2 LAST PATH I145
J 0
(-600 2225);
DISPLAY 1.021277 (-600 2225);
PAINT ORANGE (-600 2225);
DISPLAY INVISIBLE (-600 2225);
FORCEPROP 2 LAST CDS_LIB mstr_standard
J 0
(-775 2150);
PAINT MONO (-775 2150);
DISPLAY INVISIBLE (-775 2150);
FORCEADD OFFPAGE..4
(-775 2250);
FORCEPROP 2 LAST $XR1 119 
J 0
(-469 2250);
DISPLAY 0.638298 (-469 2250);
PAINT MONO (-469 2250);
FORCEPROP 2 LAST $XR0 157 
J 0
(-589 2250);
DISPLAY 0.638298 (-589 2250);
PAINT MONO (-589 2250);
FORCEPROP 1 LAST COMMENT_BODY TRUE
J 0
(-800 2150);
DISPLAY 1.404255 (-800 2150);
PAINT PEACH (-800 2150);
DISPLAY INVISIBLE (-800 2150);
FORCEPROP 1 LAST OFFPAGE TRUE
J 0
(-450 2125);
PAINT GREEN (-450 2125);
DISPLAY INVISIBLE (-450 2125);
FORCEPROP 2 LAST PATH I146
J 0
(-600 2325);
DISPLAY 1.021277 (-600 2325);
PAINT ORANGE (-600 2325);
DISPLAY INVISIBLE (-600 2325);
FORCEPROP 2 LAST CDS_LIB mstr_standard
J 0
(-775 2250);
PAINT MONO (-775 2250);
DISPLAY INVISIBLE (-775 2250);
FORCEADD OFFPAGE..4
(-775 2500);
FORCEPROP 2 LAST $XR1 144 
J 0
(-439 2500);
DISPLAY 0.638298 (-439 2500);
PAINT MONO (-439 2500);
FORCEPROP 2 LAST $XR0 157 
J 0
(-559 2500);
DISPLAY 0.638298 (-559 2500);
PAINT MONO (-559 2500);
FORCEPROP 1 LAST COMMENT_BODY TRUE
J 0
(-800 2400);
DISPLAY 1.404255 (-800 2400);
PAINT PEACH (-800 2400);
DISPLAY INVISIBLE (-800 2400);
FORCEPROP 1 LAST OFFPAGE TRUE
J 0
(-450 2375);
PAINT GREEN (-450 2375);
DISPLAY INVISIBLE (-450 2375);
FORCEPROP 2 LAST PATH I148
J 0
(-600 2575);
DISPLAY 1.021277 (-600 2575);
PAINT ORANGE (-600 2575);
DISPLAY INVISIBLE (-600 2575);
FORCEPROP 2 LAST CDS_LIB mstr_standard
J 0
(-775 2500);
PAINT MONO (-775 2500);
DISPLAY INVISIBLE (-775 2500);
FORCEADD OFFPAGE..2
(-775 2400);
FORCEPROP 2 LAST $XR1 177 
J 0
(-466 2400);
DISPLAY 0.638298 (-466 2400);
PAINT MONO (-466 2400);
FORCEPROP 2 LAST $XR0 147 
J 0
(-586 2400);
DISPLAY 0.638298 (-586 2400);
PAINT MONO (-586 2400);
FORCEPROP 1 LAST COMMENT_BODY TRUE
J 0
(-820 2305);
DISPLAY 1.404255 (-820 2305);
PAINT PEACH (-820 2305);
DISPLAY INVISIBLE (-820 2305);
FORCEPROP 1 LAST OFFPAGE TRUE
J 0
(-450 2275);
PAINT GREEN (-450 2275);
DISPLAY INVISIBLE (-450 2275);
FORCEPROP 2 LAST PATH I150
J 0
(-600 2475);
DISPLAY 1.021277 (-600 2475);
PAINT ORANGE (-600 2475);
DISPLAY INVISIBLE (-600 2475);
FORCEPROP 2 LAST CDS_LIB mstr_standard
J 0
(-775 2400);
PAINT MONO (-775 2400);
DISPLAY INVISIBLE (-775 2400);
FORCEADD OFFPAGE..2
(-775 2450);
FORCEPROP 2 LAST $XR2 170 
J 0
(-346 2450);
DISPLAY 0.638298 (-346 2450);
PAINT MONO (-346 2450);
FORCEPROP 2 LAST $XR1 120 
J 0
(-466 2450);
DISPLAY 0.638298 (-466 2450);
PAINT MONO (-466 2450);
FORCEPROP 2 LAST $XR0 145 
J 0
(-586 2450);
DISPLAY 0.638298 (-586 2450);
PAINT MONO (-586 2450);
FORCEPROP 1 LAST COMMENT_BODY TRUE
J 0
(-820 2355);
DISPLAY 1.404255 (-820 2355);
PAINT PEACH (-820 2355);
DISPLAY INVISIBLE (-820 2355);
FORCEPROP 1 LAST OFFPAGE TRUE
J 0
(-450 2325);
PAINT GREEN (-450 2325);
DISPLAY INVISIBLE (-450 2325);
FORCEPROP 2 LAST PATH I151
J 0
(-600 2525);
DISPLAY 1.021277 (-600 2525);
PAINT ORANGE (-600 2525);
DISPLAY INVISIBLE (-600 2525);
FORCEPROP 2 LAST CDS_LIB mstr_standard
J 0
(-775 2450);
PAINT MONO (-775 2450);
DISPLAY INVISIBLE (-775 2450);
FORCEADD OFFPAGE..4
(-775 2900);
FORCEPROP 2 LAST $XR2 147 
J 0
(-349 2900);
DISPLAY 0.638298 (-349 2900);
PAINT MONO (-349 2900);
FORCEPROP 2 LAST $XR1 182 
J 0
(-469 2900);
DISPLAY 0.638298 (-469 2900);
PAINT MONO (-469 2900);
FORCEPROP 2 LAST $XR0 133 
J 0
(-589 2900);
DISPLAY 0.638298 (-589 2900);
PAINT MONO (-589 2900);
FORCEPROP 1 LAST COMMENT_BODY TRUE
J 0
(-800 2800);
DISPLAY 1.404255 (-800 2800);
PAINT PEACH (-800 2800);
DISPLAY INVISIBLE (-800 2800);
FORCEPROP 1 LAST OFFPAGE TRUE
J 0
(-450 2775);
PAINT GREEN (-450 2775);
DISPLAY INVISIBLE (-450 2775);
FORCEPROP 2 LAST PATH I154
J 0
(-600 2975);
DISPLAY 1.021277 (-600 2975);
PAINT ORANGE (-600 2975);
DISPLAY INVISIBLE (-600 2975);
FORCEPROP 2 LAST CDS_LIB mstr_standard
J 0
(-775 2900);
PAINT MONO (-775 2900);
DISPLAY INVISIBLE (-775 2900);
FORCEADD OFFPAGE..4
(-775 2850);
FORCEPROP 2 LAST $XR2 147 
J 0
(-229 2850);
DISPLAY 0.638298 (-229 2850);
PAINT MONO (-229 2850);
FORCEPROP 2 LAST $XR1 182 
J 0
(-349 2850);
DISPLAY 0.638298 (-349 2850);
PAINT MONO (-349 2850);
FORCEPROP 2 LAST $XR0 133 
J 0
(-469 2850);
DISPLAY 0.638298 (-469 2850);
PAINT MONO (-469 2850);
FORCEPROP 1 LAST COMMENT_BODY TRUE
J 0
(-800 2750);
DISPLAY 1.404255 (-800 2750);
PAINT PEACH (-800 2750);
DISPLAY INVISIBLE (-800 2750);
FORCEPROP 1 LAST OFFPAGE TRUE
J 0
(-450 2725);
PAINT GREEN (-450 2725);
DISPLAY INVISIBLE (-450 2725);
FORCEPROP 2 LAST PATH I155
J 0
(-600 2925);
DISPLAY 1.021277 (-600 2925);
PAINT ORANGE (-600 2925);
DISPLAY INVISIBLE (-600 2925);
FORCEPROP 2 LAST CDS_LIB mstr_standard
J 0
(-775 2850);
PAINT MONO (-775 2850);
DISPLAY INVISIBLE (-775 2850);
FORCEADD OFFPAGE..2
(-775 2750);
FORCEPROP 2 LAST $XR0 178 
J 0
(-586 2750);
DISPLAY 0.638298 (-586 2750);
PAINT MONO (-586 2750);
FORCEPROP 1 LAST COMMENT_BODY TRUE
J 0
(-820 2655);
DISPLAY 0.872340 (-820 2655);
PAINT GREEN (-820 2655);
DISPLAY INVISIBLE (-820 2655);
FORCEPROP 1 LAST OFFPAGE TRUE
J 0
(-450 2625);
DISPLAY 0.872340 (-450 2625);
PAINT GREEN (-450 2625);
DISPLAY INVISIBLE (-450 2625);
FORCEPROP 2 LAST PATH I156
J 0
(-600 2825);
DISPLAY 1.021277 (-600 2825);
PAINT ORANGE (-600 2825);
DISPLAY INVISIBLE (-600 2825);
FORCEPROP 2 LAST CDS_LIB mstr_standard
J 0
(-775 2750);
PAINT MONO (-775 2750);
DISPLAY INVISIBLE (-775 2750);
FORCEADD OFFPAGE..2
(-775 3000);
FORCEPROP 2 LAST $XR1 151 
J 0
(-466 3000);
DISPLAY 0.638298 (-466 3000);
PAINT MONO (-466 3000);
FORCEPROP 2 LAST $XR0 146 
J 0
(-586 3000);
DISPLAY 0.638298 (-586 3000);
PAINT MONO (-586 3000);
FORCEPROP 1 LAST COMMENT_BODY TRUE
J 0
(-820 2905);
DISPLAY 1.404255 (-820 2905);
PAINT PEACH (-820 2905);
DISPLAY INVISIBLE (-820 2905);
FORCEPROP 1 LAST OFFPAGE TRUE
J 0
(-450 2875);
PAINT GREEN (-450 2875);
DISPLAY INVISIBLE (-450 2875);
FORCEPROP 2 LAST PATH I158
J 0
(-600 3075);
DISPLAY 1.021277 (-600 3075);
PAINT ORANGE (-600 3075);
DISPLAY INVISIBLE (-600 3075);
FORCEPROP 2 LAST CDS_LIB mstr_standard
J 0
(-775 3000);
PAINT MONO (-775 3000);
DISPLAY INVISIBLE (-775 3000);
FORCEADD OFFPAGE..4
(-775 3150);
FORCEPROP 2 LAST $XR1 191 
J 0
(-469 3150);
DISPLAY 0.638298 (-469 3150);
PAINT MONO (-469 3150);
FORCEPROP 2 LAST $XR0 145 
J 0
(-589 3150);
DISPLAY 0.638298 (-589 3150);
PAINT MONO (-589 3150);
FORCEPROP 1 LAST COMMENT_BODY TRUE
J 0
(-800 3050);
DISPLAY 1.404255 (-800 3050);
PAINT PEACH (-800 3050);
DISPLAY INVISIBLE (-800 3050);
FORCEPROP 1 LAST OFFPAGE TRUE
J 0
(-450 3025);
DISPLAY 1.404255 (-450 3025);
PAINT GREEN (-450 3025);
DISPLAY INVISIBLE (-450 3025);
FORCEPROP 2 LAST PATH I159
J 0
(-600 3225);
DISPLAY 1.021277 (-600 3225);
PAINT ORANGE (-600 3225);
DISPLAY INVISIBLE (-600 3225);
FORCEPROP 2 LAST CDS_LIB mstr_standard
J 0
(-775 3150);
PAINT MONO (-775 3150);
DISPLAY INVISIBLE (-775 3150);
FORCEADD OFFPAGE..2
(-775 2350);
FORCEPROP 2 LAST $XR2 190 
J 0
(-346 2350);
DISPLAY 0.638298 (-346 2350);
PAINT MONO (-346 2350);
FORCEPROP 2 LAST $XR1 157 
J 0
(-466 2350);
DISPLAY 0.638298 (-466 2350);
PAINT MONO (-466 2350);
FORCEPROP 2 LAST $XR0 146 
J 0
(-586 2350);
DISPLAY 0.638298 (-586 2350);
PAINT MONO (-586 2350);
FORCEPROP 1 LAST COMMENT_BODY TRUE
J 0
(-820 2255);
DISPLAY 1.404255 (-820 2255);
PAINT PEACH (-820 2255);
DISPLAY INVISIBLE (-820 2255);
FORCEPROP 1 LAST OFFPAGE TRUE
J 0
(-450 2225);
PAINT GREEN (-450 2225);
DISPLAY INVISIBLE (-450 2225);
FORCEPROP 2 LAST PATH I161
J 0
(-600 2425);
DISPLAY 1.021277 (-600 2425);
PAINT ORANGE (-600 2425);
DISPLAY INVISIBLE (-600 2425);
FORCEPROP 2 LAST CDS_LIB mstr_standard
J 0
(-775 2350);
PAINT MONO (-775 2350);
DISPLAY INVISIBLE (-775 2350);
FORCEADD OFFPAGE..4
(-775 2550);
FORCEPROP 2 LAST $XR1 146 
J 0
(-439 2550);
DISPLAY 0.638298 (-439 2550);
PAINT MONO (-439 2550);
FORCEPROP 2 LAST $XR0 139 
J 0
(-559 2550);
DISPLAY 0.638298 (-559 2550);
PAINT MONO (-559 2550);
FORCEPROP 1 LAST COMMENT_BODY TRUE
J 0
(-800 2450);
DISPLAY 1.404255 (-800 2450);
PAINT PEACH (-800 2450);
DISPLAY INVISIBLE (-800 2450);
FORCEPROP 1 LAST OFFPAGE TRUE
J 0
(-450 2425);
PAINT GREEN (-450 2425);
DISPLAY INVISIBLE (-450 2425);
FORCEPROP 2 LAST PATH I164
J 0
(-600 2625);
DISPLAY 1.021277 (-600 2625);
PAINT ORANGE (-600 2625);
DISPLAY INVISIBLE (-600 2625);
FORCEPROP 2 LAST CDS_LIB mstr_standard
J 0
(-775 2550);
PAINT MONO (-775 2550);
DISPLAY INVISIBLE (-775 2550);
FORCEADD OFFPAGE..5
(-7175 2700);
FORCEPROP 2 LAST $XR1 175 
J 0
(-7580 2700);
DISPLAY 0.638298 (-7580 2700);
PAINT MONO (-7580 2700);
FORCEPROP 2 LAST $XR0 136 
J 0
(-7460 2700);
DISPLAY 0.638298 (-7460 2700);
PAINT MONO (-7460 2700);
FORCEPROP 1 LAST COMMENT_BODY TRUE
J 0
(-7075 2625);
DISPLAY 0.872340 (-7075 2625);
PAINT GREEN (-7075 2625);
DISPLAY INVISIBLE (-7075 2625);
FORCEPROP 1 LAST OFFPAGE TRUE
J 0
(-6850 2575);
DISPLAY 0.872340 (-6850 2575);
PAINT GREEN (-6850 2575);
DISPLAY INVISIBLE (-6850 2575);
FORCEPROP 2 LAST PATH I166
J 0
(-7125 2775);
DISPLAY 1.021277 (-7125 2775);
PAINT ORANGE (-7125 2775);
DISPLAY INVISIBLE (-7125 2775);
FORCEPROP 2 LAST CDS_LIB mstr_standard
J 0
(-7175 2700);
PAINT MONO (-7175 2700);
DISPLAY INVISIBLE (-7175 2700);
FORCEADD OFFPAGE..4
R 2
(-7550 4050);
FORCEPROP 2 LAST $XR0 137 
J 0
(-7802 4050);
DISPLAY 0.638298 (-7802 4050);
PAINT MONO (-7802 4050);
FORCEPROP 2 LAST CDS_LIB mstr_standard
J 0
(-7550 4050);
PAINT MONO (-7550 4050);
DISPLAY INVISIBLE (-7550 4050);
FORCEPROP 2 LAST PATH I170
J 0
(-7500 4125);
DISPLAY 1.021277 (-7500 4125);
PAINT ORANGE (-7500 4125);
DISPLAY INVISIBLE (-7500 4125);
FORCEPROP 1 LAST OFFPAGE TRUE
J 2
(-7875 3925);
DISPLAY 0.872340 (-7875 3925);
PAINT GREEN (-7875 3925);
DISPLAY INVISIBLE (-7875 3925);
FORCEPROP 1 LAST COMMENT_BODY TRUE
J 2
(-7525 3950);
DISPLAY 0.872340 (-7525 3950);
PAINT GREEN (-7525 3950);
DISPLAY INVISIBLE (-7525 3950);
FORCEADD OFFPAGE..2
(-400 4150);
FORCEPROP 2 LAST $XR2 170 
J 0
(-121 4186);
DISPLAY 0.638298 (-121 4186);
PAINT MONO (-121 4186);
FORCEPROP 2 LAST $XR1 145 
J 0
(-121 4114);
DISPLAY 0.638298 (-121 4114);
PAINT MONO (-121 4114);
FORCEPROP 2 LAST $XR0 119 
J 0
(-121 4150);
DISPLAY 0.638298 (-121 4150);
PAINT MONO (-121 4150);
FORCEPROP 2 LAST CDS_LIB mstr_standard
J 0
(-400 4150);
PAINT MONO (-400 4150);
DISPLAY INVISIBLE (-400 4150);
FORCEPROP 2 LAST PATH I171
J 0
(-225 4225);
DISPLAY 1.021277 (-225 4225);
PAINT ORANGE (-225 4225);
DISPLAY INVISIBLE (-225 4225);
FORCEPROP 1 LAST OFFPAGE TRUE
J 0
(-75 4025);
PAINT GREEN (-75 4025);
DISPLAY INVISIBLE (-75 4025);
FORCEPROP 1 LAST COMMENT_BODY TRUE
J 0
(-445 4055);
DISPLAY 1.404255 (-445 4055);
PAINT PEACH (-445 4055);
DISPLAY INVISIBLE (-445 4055);
FORCEADD RES..1
(-1450 2200);
FORCEPROP 1 LAST LOCATION R2M3
J 0
(-1500 2275);
DISPLAY 0.617021 (-1500 2275);
PAINT AQUA (-1500 2275);
FORCEPROP 1 LASTPIN (-1550 2200) $PN 1
J 0
(-1538 2212);
DISPLAY 0.617021 (-1538 2212);
PAINT ORANGE (-1538 2212);
FORCEPROP 1 LAST PACK_TYPE 0402
J 0
(-1375 2150);
DISPLAY 0.617021 (-1375 2150);
PAINT SKYBLUE (-1375 2150);
FORCEPROP 1 LASTPIN (-1350 2200) $PN 2
J 0
(-1388 2212);
DISPLAY 0.617021 (-1388 2212);
PAINT ORANGE (-1388 2212);
FORCEPROP 1 LAST WATTAGE 1/16W
J 2
(-1650 2200);
DISPLAY 0.617021 (-1650 2200);
PAINT SKYBLUE (-1650 2200);
FORCEPROP 1 LAST VALUE 33.2
J 2
(-1550 2200);
DISPLAY 0.617021 (-1550 2200);
PAINT SKYBLUE (-1550 2200);
FORCEPROP 1 LAST TOLERANCE 1%
J 0
(-1600 2150);
DISPLAY 0.617021 (-1600 2150);
PAINT SKYBLUE (-1600 2150);
FORCEPROP 1 LAST MATERIAL CHIP
J 0
(-1500 2150);
DISPLAY 0.617021 (-1500 2150);
PAINT SKYBLUE (-1500 2150);
FORCEPROP 1 LAST PART_NUMBER G21796-074
J 0
(-1275 2150);
DISPLAY 0.617021 (-1275 2150);
PAINT BLUE (-1275 2150);
FORCEPROP 1 LAST PATH I172
J 0
(-1500 2350);
DISPLAY 0.978723 (-1500 2350);
PAINT WHITE (-1500 2350);
DISPLAY INVISIBLE (-1500 2350);
FORCEPROP 2 LAST ROOM CPLD
J 0
(-1500 2340);
DISPLAY 0.787234 (-1500 2340);
PAINT SKYBLUE (-1500 2340);
DISPLAY INVISIBLE (-1500 2340);
FORCEPROP 2 LAST SEC_TYPE 0402
J 0
(-1500 2400);
DISPLAY 1.021277 (-1500 2400);
PAINT ORANGE (-1500 2400);
DISPLAY INVISIBLE (-1500 2400);
FORCEPROP 2 LAST SEC 1
J 0
(-1500 2400);
DISPLAY 0.680851 (-1500 2400);
PAINT MONO (-1500 2400);
DISPLAY INVISIBLE (-1500 2400);
FORCEPROP 2 LAST CDS_LIB mstr_discrete
J 0
(-1450 2200);
PAINT MONO (-1450 2200);
DISPLAY INVISIBLE (-1450 2200);
FORCEPROP 2 LAST CDS_LOCATION R2M3
J 0
(-1475 2225);
DISPLAY 0.617021 (-1475 2225);
PAINT AQUA (-1475 2225);
DISPLAY INVISIBLE (-1475 2225);
FORCEADD RES..1
(-1550 4400);
FORCEPROP 1 LAST VALUE 33.2
J 2
(-1150 4450);
DISPLAY 0.617021 (-1150 4450);
PAINT SKYBLUE (-1150 4450);
FORCEPROP 1 LAST MATERIAL CHIP
J 0
(-1475 4500);
DISPLAY 0.617021 (-1475 4500);
PAINT SKYBLUE (-1475 4500);
FORCEPROP 1 LAST PART_NUMBER G21796-074
J 0
(-1475 4450);
DISPLAY 0.617021 (-1475 4450);
PAINT BLUE (-1475 4450);
FORCEPROP 1 LASTPIN (-1450 4400) $PN 2
J 0
(-1488 4412);
DISPLAY 0.617021 (-1488 4412);
PAINT ORANGE (-1488 4412);
FORCEPROP 1 LAST TOLERANCE 1%
J 0
(-1825 4475);
DISPLAY 0.617021 (-1825 4475);
PAINT SKYBLUE (-1825 4475);
FORCEPROP 1 LAST WATTAGE 1/16W
J 2
(-1625 4475);
DISPLAY 0.617021 (-1625 4475);
PAINT SKYBLUE (-1625 4475);
FORCEPROP 1 LAST LOCATION R2N1
J 0
(-1600 4450);
DISPLAY 0.617021 (-1600 4450);
PAINT AQUA (-1600 4450);
FORCEPROP 1 LAST PACK_TYPE 0402
J 0
(-1350 4500);
DISPLAY 0.617021 (-1350 4500);
PAINT SKYBLUE (-1350 4500);
FORCEPROP 1 LASTPIN (-1650 4400) $PN 1
J 0
(-1638 4412);
DISPLAY 0.617021 (-1638 4412);
PAINT ORANGE (-1638 4412);
FORCEPROP 2 LAST SEC 1
J 0
(-1600 4600);
DISPLAY 0.680851 (-1600 4600);
PAINT MONO (-1600 4600);
DISPLAY INVISIBLE (-1600 4600);
FORCEPROP 2 LAST SEC_TYPE 0402
J 0
(-1600 4600);
DISPLAY 1.021277 (-1600 4600);
PAINT ORANGE (-1600 4600);
DISPLAY INVISIBLE (-1600 4600);
FORCEPROP 2 LAST ROOM CPLD
J 0
(-1600 4540);
DISPLAY 0.787234 (-1600 4540);
PAINT SKYBLUE (-1600 4540);
DISPLAY INVISIBLE (-1600 4540);
FORCEPROP 1 LAST PATH I173
J 0
(-1600 4550);
DISPLAY 0.978723 (-1600 4550);
PAINT WHITE (-1600 4550);
DISPLAY INVISIBLE (-1600 4550);
FORCEPROP 2 LAST CDS_LOCATION R2N1
J 0
(-1600 4450);
DISPLAY 0.617021 (-1600 4450);
PAINT AQUA (-1600 4450);
DISPLAY INVISIBLE (-1600 4450);
FORCEPROP 2 LAST CDS_LIB mstr_discrete
J 0
(-1550 4400);
PAINT MONO (-1550 4400);
DISPLAY INVISIBLE (-1550 4400);
FORCEADD RES..1
(-1475 2950);
FORCEPROP 1 LAST PACK_TYPE 0402
J 0
(-1400 2900);
DISPLAY 0.617021 (-1400 2900);
PAINT SKYBLUE (-1400 2900);
FORCEPROP 1 LAST MATERIAL CHIP
J 0
(-1525 2900);
DISPLAY 0.617021 (-1525 2900);
PAINT SKYBLUE (-1525 2900);
FORCEPROP 1 LAST TOLERANCE 1%
J 0
(-1625 2900);
DISPLAY 0.617021 (-1625 2900);
PAINT SKYBLUE (-1625 2900);
FORCEPROP 1 LAST VALUE 33.2
J 2
(-1575 2950);
DISPLAY 0.617021 (-1575 2950);
PAINT SKYBLUE (-1575 2950);
FORCEPROP 1 LASTPIN (-1575 2950) $PN 1
J 0
(-1563 2962);
DISPLAY 0.617021 (-1563 2962);
PAINT ORANGE (-1563 2962);
FORCEPROP 1 LASTPIN (-1375 2950) $PN 2
J 0
(-1413 2962);
DISPLAY 0.617021 (-1413 2962);
PAINT ORANGE (-1413 2962);
FORCEPROP 1 LAST LOCATION R2M7
J 0
(-1525 3025);
DISPLAY 0.617021 (-1525 3025);
PAINT AQUA (-1525 3025);
FORCEPROP 1 LAST WATTAGE 1/16W
J 2
(-1675 2950);
DISPLAY 0.617021 (-1675 2950);
PAINT SKYBLUE (-1675 2950);
FORCEPROP 1 LAST PART_NUMBER G21796-074
J 0
(-1300 2900);
DISPLAY 0.617021 (-1300 2900);
PAINT BLUE (-1300 2900);
FORCEPROP 2 LAST ROOM CPLD
J 0
(-1525 3090);
DISPLAY 0.787234 (-1525 3090);
PAINT SKYBLUE (-1525 3090);
DISPLAY INVISIBLE (-1525 3090);
FORCEPROP 1 LAST PATH I174
J 0
(-1525 3100);
DISPLAY 0.978723 (-1525 3100);
PAINT WHITE (-1525 3100);
DISPLAY INVISIBLE (-1525 3100);
FORCEPROP 2 LAST SEC 1
J 0
(-1525 3150);
DISPLAY 0.680851 (-1525 3150);
PAINT MONO (-1525 3150);
DISPLAY INVISIBLE (-1525 3150);
FORCEPROP 2 LAST SEC_TYPE 0402
J 0
(-1525 3150);
DISPLAY 1.021277 (-1525 3150);
PAINT ORANGE (-1525 3150);
DISPLAY INVISIBLE (-1525 3150);
FORCEPROP 2 LAST CDS_LIB mstr_discrete
J 0
(-1475 2950);
PAINT MONO (-1475 2950);
DISPLAY INVISIBLE (-1475 2950);
FORCEPROP 2 LAST CDS_LOCATION R2M7
J 0
(-1500 2975);
DISPLAY 0.617021 (-1500 2975);
PAINT AQUA (-1500 2975);
DISPLAY INVISIBLE (-1500 2975);
FORCEADD FET_N_DUAL..5
(-4725 725);
FORCEPROP 1 LAST PART_NUMBER E40049-001
J 0
(-4525 525);
DISPLAY 0.617021 (-4525 525);
PAINT BLUE (-4525 525);
FORCEPROP 1 LAST MATERIAL FET
J 0
(-4525 625);
DISPLAY 0.617021 (-4525 625);
PAINT SKYBLUE (-4525 625);
FORCEPROP 1 LAST VALUE NTJD4001N
J 0
(-4525 675);
DISPLAY 0.617021 (-4525 675);
PAINT SKYBLUE (-4525 675);
FORCEPROP 1 LAST LOCATION Q9A2
J 0
(-4525 725);
DISPLAY 0.617021 (-4525 725);
PAINT AQUA (-4525 725);
FORCEPROP 1 LASTPIN (-4725 925) $PN 6
J 2
(-4672 890);
DISPLAY 0.617021 (-4672 890);
PAINT WHITE (-4672 890);
FORCEPROP 1 LASTPIN (-4725 525) $PN 1
J 2
(-4667 525);
DISPLAY 0.617021 (-4667 525);
PAINT WHITE (-4667 525);
FORCEPROP 1 LASTPIN (-4925 625) $PN 2
J 2
(-4922 640);
DISPLAY 0.617021 (-4922 640);
PAINT WHITE (-4922 640);
FORCEPROP 2 LAST CDS_LOCATION Q9A2
J 0
(-4525 725);
DISPLAY 0.617021 (-4525 725);
PAINT AQUA (-4525 725);
DISPLAY INVISIBLE (-4525 725);
FORCEPROP 1 LAST PATH I175
J 0
(-4525 775);
DISPLAY 0.978723 (-4525 775);
PAINT BLUE (-4525 775);
DISPLAY INVISIBLE (-4525 775);
FORCEPROP 0 LAST ROOM SB
J 0
(-4525 825);
DISPLAY 1.021277 (-4525 825);
PAINT ORANGE (-4525 825);
DISPLAY INVISIBLE (-4525 825);
FORCEPROP 2 LAST SEC_TYPE SMLF
J 0
(-4525 825);
DISPLAY 1.021277 (-4525 825);
PAINT ORANGE (-4525 825);
DISPLAY INVISIBLE (-4525 825);
FORCEPROP 0 LAST BOM_COST SB
J 0
(-4525 925);
DISPLAY 1.021277 (-4525 925);
PAINT ORANGE (-4525 925);
DISPLAY INVISIBLE (-4525 925);
FORCEPROP 2 LAST SEC 1
J 0
(-4525 825);
DISPLAY 0.680851 (-4525 825);
PAINT MONO (-4525 825);
DISPLAY INVISIBLE (-4525 825);
FORCEPROP 2 LAST CDS_LIB mstr_discrete
J 0
(-4725 725);
PAINT MONO (-4725 725);
DISPLAY INVISIBLE (-4725 725);
FORCEPROP 1 LAST PACK_TYPE SMLF
J 0
(-4525 575);
DISPLAY 0.978723 (-4525 575);
PAINT SKYBLUE (-4525 575);
DISPLAY INVISIBLE (-4525 575);
FORCEADD OFFPAGE..1
(-5600 625);
FORCEPROP 2 LAST $XR0 119 
J 0
(-5852 625);
DISPLAY 0.638298 (-5852 625);
PAINT MONO (-5852 625);
FORCEPROP 1 LAST COMMENT_BODY TRUE
J 0
(-5475 525);
DISPLAY 0.872340 (-5475 525);
PAINT GREEN (-5475 525);
DISPLAY INVISIBLE (-5475 525);
FORCEPROP 1 LAST OFFPAGE TRUE
J 0
(-5275 500);
DISPLAY 0.872340 (-5275 500);
PAINT GREEN (-5275 500);
DISPLAY INVISIBLE (-5275 500);
FORCEPROP 2 LAST PATH I176
J 0
(-5550 700);
DISPLAY 1.021277 (-5550 700);
PAINT ORANGE (-5550 700);
DISPLAY INVISIBLE (-5550 700);
FORCEPROP 2 LAST CDS_LIB mstr_standard
J 0
(-5600 625);
PAINT MONO (-5600 625);
DISPLAY INVISIBLE (-5600 625);
FORCEADD P3V3_STBY..1
(-2700 1700);
FORCEPROP 3 LASTPIN (-2700 1650) SIG_NAME P3V3_STBY\g
J 0
(-2690 1660);
DISPLAY 0.659574 (-2690 1660);
PAINT MONO (-2690 1660);
DISPLAY INVISIBLE (-2690 1660);
FORCEPROP 1 LAST PATH I177
J 0
(-2655 1702);
DISPLAY 0.340426 (-2655 1702);
PAINT GREEN (-2655 1702);
DISPLAY INVISIBLE (-2655 1702);
FORCEPROP 1 LAST VOLTAGE 3.3V
J 0
(-2745 1657);
DISPLAY 0.340426 (-2745 1657);
PAINT SKYBLUE (-2745 1657);
DISPLAY INVISIBLE (-2745 1657);
FORCEPROP 2 LAST CDS_LIB mstr_symbols
J 0
(-2700 1700);
PAINT MONO (-2700 1700);
DISPLAY INVISIBLE (-2700 1700);
FORCEPROP 1 LAST SIZE 1B
J 0
(-2655 1722);
DISPLAY 0.340426 (-2655 1722);
PAINT GREEN (-2655 1722);
DISPLAY INVISIBLE (-2655 1722);
FORCEPROP 1 LAST BODY_TYPE PLUMBING
J 0
(-2745 1657);
DISPLAY 0.340426 (-2745 1657);
PAINT GREEN (-2745 1657);
DISPLAY INVISIBLE (-2745 1657);
FORCEPROP 1 LAST HDL_POWER P3V3_STBY
J 0
(-3000 1575);
DISPLAY 0.872340 (-3000 1575);
PAINT ORANGE (-3000 1575);
DISPLAY INVISIBLE (-3000 1575);
FORCEADD RES..1
(-2900 1525);
FORCEPROP 1 LAST PACK_TYPE 0402
J 0
(-2775 1375);
DISPLAY 0.617021 (-2775 1375);
PAINT SKYBLUE (-2775 1375);
FORCEPROP 1 LASTPIN (-3000 1525) $PN 1
J 0
(-2988 1537);
DISPLAY 0.617021 (-2988 1537);
PAINT ORANGE (-2988 1537);
FORCEPROP 1 LAST WATTAGE 1/16W
J 2
(-2925 1375);
DISPLAY 0.617021 (-2925 1375);
PAINT SKYBLUE (-2925 1375);
FORCEPROP 1 LAST VALUE 221
J 2
(-2925 1425);
DISPLAY 0.617021 (-2925 1425);
PAINT SKYBLUE (-2925 1425);
FORCEPROP 1 LASTPIN (-2800 1525) $PN 2
J 0
(-2838 1537);
DISPLAY 0.617021 (-2838 1537);
PAINT ORANGE (-2838 1537);
FORCEPROP 1 LAST MATERIAL CHIP
J 0
(-2900 1375);
DISPLAY 0.617021 (-2900 1375);
PAINT SKYBLUE (-2900 1375);
FORCEPROP 1 LAST TOLERANCE 1.0%
J 0
(-2900 1425);
DISPLAY 0.617021 (-2900 1425);
PAINT SKYBLUE (-2900 1425);
FORCEPROP 1 LAST PART_NUMBER G21796-271
J 0
(-2775 1425);
DISPLAY 0.617021 (-2775 1425);
PAINT BLUE (-2775 1425);
FORCEPROP 1 LAST LOCATION R9A20
J 0
(-2950 1575);
DISPLAY 0.617021 (-2950 1575);
PAINT AQUA (-2950 1575);
FORCEPROP 2 LAST SEC 1
J 0
(-2950 1725);
DISPLAY 0.680851 (-2950 1725);
PAINT MONO (-2950 1725);
DISPLAY INVISIBLE (-2950 1725);
FORCEPROP 2 LAST BOM_COST SB
J 0
(-2950 1725);
DISPLAY 1.021277 (-2950 1725);
PAINT ORANGE (-2950 1725);
DISPLAY INVISIBLE (-2950 1725);
FORCEPROP 2 LAST SEC_TYPE 0402
J 0
(-2950 1725);
DISPLAY 1.021277 (-2950 1725);
PAINT ORANGE (-2950 1725);
DISPLAY INVISIBLE (-2950 1725);
FORCEPROP 2 LAST CDS_LIB mstr_discrete
J 0
(-2900 1525);
PAINT MONO (-2900 1525);
DISPLAY INVISIBLE (-2900 1525);
FORCEPROP 2 LAST CDS_LOCATION R9A20
J 0
(-2950 1575);
DISPLAY 0.617021 (-2950 1575);
PAINT AQUA (-2950 1575);
DISPLAY INVISIBLE (-2950 1575);
FORCEPROP 1 LAST PATH I178
J 0
(-2950 1675);
DISPLAY 0.978723 (-2950 1675);
PAINT WHITE (-2950 1675);
DISPLAY INVISIBLE (-2950 1675);
FORCEPROP 2 LAST ROOM SB
J 0
(-2950 1675);
DISPLAY 1.021277 (-2950 1675);
PAINT ORANGE (-2950 1675);
DISPLAY INVISIBLE (-2950 1675);
FORCEADD LED..3
(-3550 1525);
FORCEPROP 2 LASTPIN (-3650 1525) $PN 2
J 2
(-3660 1535);
DISPLAY 0.617021 (-3660 1535);
PAINT ORANGE (-3660 1535);
FORCEPROP 2 LASTPIN (-3450 1525) $PN 1
J 0
(-3440 1535);
DISPLAY 0.617021 (-3440 1535);
PAINT ORANGE (-3440 1535);
FORCEPROP 1 LAST PART_NUMBER C97278-010
J 0
(-3550 1400);
DISPLAY 0.617021 (-3550 1400);
PAINT BLUE (-3550 1400);
FORCEPROP 1 LAST LOCATION DS9A5
J 0
(-3650 1725);
DISPLAY 0.617021 (-3650 1725);
PAINT AQUA (-3650 1725);
FORCEPROP 1 LAST MATERIAL IC
J 0
(-3650 1675);
DISPLAY 0.617021 (-3650 1675);
PAINT SKYBLUE (-3650 1675);
FORCEPROP 1 LAST COLOR GREEN
J 0
(-3650 1625);
DISPLAY 0.617021 (-3650 1625);
PAINT BLUE (-3650 1625);
FORCEPROP 1 LAST PATH I179
J 0
(-3200 1675);
DISPLAY 0.978723 (-3200 1675);
PAINT BLUE (-3200 1675);
DISPLAY INVISIBLE (-3200 1675);
FORCEPROP 2 LAST SEC 1
J 0
(-3650 1775);
DISPLAY 0.680851 (-3650 1775);
PAINT MONO (-3650 1775);
DISPLAY INVISIBLE (-3650 1775);
FORCEPROP 2 LAST ROOM SB
J 0
(-3650 1775);
DISPLAY 1.021277 (-3650 1775);
PAINT ORANGE (-3650 1775);
DISPLAY INVISIBLE (-3650 1775);
FORCEPROP 1 LAST PACK_TYPE A1LF
J 0
(-3650 1775);
DISPLAY 0.978723 (-3650 1775);
PAINT SKYBLUE (-3650 1775);
DISPLAY INVISIBLE (-3650 1775);
FORCEPROP 2 LAST SEC_TYPE A1LF
J 0
(-3650 1775);
DISPLAY 1.021277 (-3650 1775);
PAINT ORANGE (-3650 1775);
DISPLAY INVISIBLE (-3650 1775);
FORCEPROP 2 LAST BOM_COST SB
J 0
(-3650 1825);
DISPLAY 1.021277 (-3650 1825);
PAINT ORANGE (-3650 1825);
DISPLAY INVISIBLE (-3650 1825);
FORCEPROP 2 LAST CDS_LOCATION DS9A5
J 0
(-3650 1725);
DISPLAY 0.617021 (-3650 1725);
PAINT AQUA (-3650 1725);
DISPLAY INVISIBLE (-3650 1725);
FORCEPROP 2 LAST CDS_LIB mstr_discrete
J 0
(-3550 1525);
PAINT MONO (-3550 1525);
DISPLAY INVISIBLE (-3550 1525);
FORCEADD FET_N_DUAL..5
(-3950 1200);
FORCEPROP 1 LAST MATERIAL FET
J 0
(-3750 1100);
DISPLAY 0.617021 (-3750 1100);
PAINT SKYBLUE (-3750 1100);
FORCEPROP 1 LAST VALUE NTJD4001N
J 0
(-3750 1150);
DISPLAY 0.617021 (-3750 1150);
PAINT SKYBLUE (-3750 1150);
FORCEPROP 1 LAST PART_NUMBER E40049-001
J 0
(-3750 1000);
DISPLAY 0.617021 (-3750 1000);
PAINT BLUE (-3750 1000);
FORCEPROP 1 LASTPIN (-3950 1400) $PN 3
J 2
(-3897 1365);
DISPLAY 0.617021 (-3897 1365);
PAINT WHITE (-3897 1365);
FORCEPROP 1 LASTPIN (-3950 1000) $PN 4
J 2
(-3892 1000);
DISPLAY 0.617021 (-3892 1000);
PAINT WHITE (-3892 1000);
FORCEPROP 1 LASTPIN (-4150 1100) $PN 5
J 2
(-4147 1115);
DISPLAY 0.617021 (-4147 1115);
PAINT WHITE (-4147 1115);
FORCEPROP 1 LAST LOCATION Q9A2
J 0
(-3750 1200);
DISPLAY 0.617021 (-3750 1200);
PAINT AQUA (-3750 1200);
FORCEPROP 2 LAST BOM_COST SB
J 0
(-3750 1300);
DISPLAY 1.021277 (-3750 1300);
PAINT ORANGE (-3750 1300);
DISPLAY INVISIBLE (-3750 1300);
FORCEPROP 2 LAST SEC_TYPE SMLF
J 0
(-3750 1300);
DISPLAY 1.021277 (-3750 1300);
PAINT ORANGE (-3750 1300);
DISPLAY INVISIBLE (-3750 1300);
FORCEPROP 2 LAST SEC 2
J 0
(-3750 1300);
DISPLAY 0.680851 (-3750 1300);
PAINT MONO (-3750 1300);
DISPLAY INVISIBLE (-3750 1300);
FORCEPROP 1 LAST PATH I180
J 0
(-3750 1250);
DISPLAY 0.978723 (-3750 1250);
PAINT BLUE (-3750 1250);
DISPLAY INVISIBLE (-3750 1250);
FORCEPROP 2 LAST ROOM SB
J 0
(-3750 1250);
DISPLAY 1.021277 (-3750 1250);
PAINT ORANGE (-3750 1250);
DISPLAY INVISIBLE (-3750 1250);
FORCEPROP 2 LAST CDS_LIB mstr_discrete
J 0
(-3950 1200);
PAINT MONO (-3950 1200);
DISPLAY INVISIBLE (-3950 1200);
FORCEPROP 2 LAST CDS_LOCATION Q9A2
J 0
(-3750 1200);
DISPLAY 0.617021 (-3750 1200);
PAINT AQUA (-3750 1200);
DISPLAY INVISIBLE (-3750 1200);
FORCEPROP 1 LAST PACK_TYPE SMLF
J 0
(-3750 1050);
DISPLAY 0.978723 (-3750 1050);
PAINT SKYBLUE (-3750 1050);
DISPLAY INVISIBLE (-3750 1050);
FORCEADD GND..1
(-3950 850);
FORCEPROP 3 LASTPIN (-3950 900) SIG_NAME GND\g
J 0
(-3940 910);
DISPLAY 0.659574 (-3940 910);
PAINT MONO (-3940 910);
DISPLAY INVISIBLE (-3940 910);
FORCEPROP 1 LAST HDL_POWER GND
J 0
(-3950 1000);
DISPLAY 0.872340 (-3950 1000);
PAINT GREEN (-3950 1000);
DISPLAY INVISIBLE (-3950 1000);
FORCEPROP 1 LAST BODY_TYPE PLUMBING
J 0
(-3995 807);
DISPLAY 0.340426 (-3995 807);
PAINT GREEN (-3995 807);
DISPLAY INVISIBLE (-3995 807);
FORCEPROP 1 LAST VOLTAGE 0.0V
J 0
(-3995 807);
DISPLAY 0.340426 (-3995 807);
PAINT SKYBLUE (-3995 807);
DISPLAY INVISIBLE (-3995 807);
FORCEPROP 2 LAST CDS_LIB mstr_symbols
J 0
(-3950 850);
PAINT MONO (-3950 850);
DISPLAY INVISIBLE (-3950 850);
FORCEPROP 1 LAST SIZE 1B
J 0
(-3875 800);
DISPLAY 0.872340 (-3875 800);
PAINT AQUA (-3875 800);
DISPLAY INVISIBLE (-3875 800);
FORCEPROP 1 LAST PATH I181
J 0
(-3875 850);
DISPLAY 0.872340 (-3875 850);
PAINT AQUA (-3875 850);
DISPLAY INVISIBLE (-3875 850);
FORCEADD P3V3_STBY..1
(-4725 1550);
FORCEPROP 3 LASTPIN (-4725 1500) SIG_NAME P3V3_STBY\g
J 0
(-4715 1510);
DISPLAY 0.659574 (-4715 1510);
PAINT MONO (-4715 1510);
DISPLAY INVISIBLE (-4715 1510);
FORCEPROP 1 LAST HDL_POWER P3V3_STBY
J 0
(-5025 1425);
DISPLAY 0.872340 (-5025 1425);
PAINT ORANGE (-5025 1425);
DISPLAY INVISIBLE (-5025 1425);
FORCEPROP 1 LAST BODY_TYPE PLUMBING
J 0
(-4770 1507);
DISPLAY 0.340426 (-4770 1507);
PAINT GREEN (-4770 1507);
DISPLAY INVISIBLE (-4770 1507);
FORCEPROP 1 LAST PATH I182
J 0
(-4680 1552);
DISPLAY 0.340426 (-4680 1552);
PAINT GREEN (-4680 1552);
DISPLAY INVISIBLE (-4680 1552);
FORCEPROP 1 LAST SIZE 1B
J 0
(-4680 1572);
DISPLAY 0.340426 (-4680 1572);
PAINT GREEN (-4680 1572);
DISPLAY INVISIBLE (-4680 1572);
FORCEPROP 2 LAST CDS_LIB mstr_symbols
J 0
(-4725 1550);
PAINT MONO (-4725 1550);
DISPLAY INVISIBLE (-4725 1550);
FORCEPROP 1 LAST VOLTAGE 3.3V
J 0
(-4770 1507);
DISPLAY 0.340426 (-4770 1507);
PAINT SKYBLUE (-4770 1507);
DISPLAY INVISIBLE (-4770 1507);
FORCEADD RES..2
(-4725 1350);
FORCEPROP 1 LAST LOCATION R9A18
J 0
(-4680 1475);
DISPLAY 0.617021 (-4680 1475);
PAINT AQUA (-4680 1475);
FORCEPROP 1 LAST PART_NUMBER G21796-072
J 0
(-4685 1225);
DISPLAY 0.617021 (-4685 1225);
PAINT BLUE (-4685 1225);
FORCEPROP 1 LAST TOLERANCE 1%
J 0
(-4680 1375);
DISPLAY 0.617021 (-4680 1375);
PAINT SKYBLUE (-4680 1375);
FORCEPROP 1 LAST VALUE 4.75K
J 0
(-4680 1425);
DISPLAY 0.617021 (-4680 1425);
PAINT SKYBLUE (-4680 1425);
FORCEPROP 1 LAST MATERIAL CHIP
J 0
(-4685 1275);
DISPLAY 0.617021 (-4685 1275);
PAINT SKYBLUE (-4685 1275);
FORCEPROP 1 LAST WATTAGE 1/16W
J 0
(-4685 1325);
DISPLAY 0.617021 (-4685 1325);
PAINT SKYBLUE (-4685 1325);
FORCEPROP 1 LASTPIN (-4725 1450) $PN 1
J 0
(-4720 1412);
DISPLAY 0.617021 (-4720 1412);
PAINT ORANGE (-4720 1412);
FORCEPROP 1 LASTPIN (-4725 1250) $PN 2
J 0
(-4720 1260);
DISPLAY 0.617021 (-4720 1260);
PAINT ORANGE (-4720 1260);
FORCEPROP 1 LAST PACK_TYPE 0402
J 0
(-4685 1175);
DISPLAY 0.617021 (-4685 1175);
PAINT SKYBLUE (-4685 1175);
FORCEPROP 0 LAST ROOM SB
J 0
(-4675 1575);
DISPLAY 1.021277 (-4675 1575);
PAINT ORANGE (-4675 1575);
DISPLAY INVISIBLE (-4675 1575);
FORCEPROP 1 LAST PATH I183
J 0
(-4675 1525);
DISPLAY 0.978723 (-4675 1525);
PAINT WHITE (-4675 1525);
DISPLAY INVISIBLE (-4675 1525);
FORCEPROP 2 LAST SEC 1
J 0
(-4675 1575);
DISPLAY 0.680851 (-4675 1575);
PAINT MONO (-4675 1575);
DISPLAY INVISIBLE (-4675 1575);
FORCEPROP 0 LAST BOM_COST SB
J 0
(-4675 1675);
DISPLAY 1.021277 (-4675 1675);
PAINT ORANGE (-4675 1675);
DISPLAY INVISIBLE (-4675 1675);
FORCEPROP 2 LAST SEC_TYPE 0402
J 0
(-4675 1575);
DISPLAY 1.021277 (-4675 1575);
PAINT ORANGE (-4675 1575);
DISPLAY INVISIBLE (-4675 1575);
FORCEPROP 2 LAST CDS_LOCATION R9A18
J 0
(-4680 1475);
DISPLAY 0.617021 (-4680 1475);
PAINT AQUA (-4680 1475);
DISPLAY INVISIBLE (-4680 1475);
FORCEPROP 2 LAST CDS_LIB mstr_discrete
J 0
(-4725 1350);
PAINT MONO (-4725 1350);
DISPLAY INVISIBLE (-4725 1350);
FORCEADD GND..1
(-4725 425);
FORCEPROP 3 LASTPIN (-4725 475) SIG_NAME GND\g
J 0
(-4715 485);
DISPLAY 0.659574 (-4715 485);
PAINT MONO (-4715 485);
DISPLAY INVISIBLE (-4715 485);
FORCEPROP 1 LAST HDL_POWER GND
J 0
(-4725 575);
DISPLAY 0.872340 (-4725 575);
PAINT GREEN (-4725 575);
DISPLAY INVISIBLE (-4725 575);
FORCEPROP 1 LAST BODY_TYPE PLUMBING
J 0
(-4770 382);
DISPLAY 0.340426 (-4770 382);
PAINT GREEN (-4770 382);
DISPLAY INVISIBLE (-4770 382);
FORCEPROP 2 LAST CDS_LIB mstr_symbols
J 0
(-4725 425);
PAINT MONO (-4725 425);
DISPLAY INVISIBLE (-4725 425);
FORCEPROP 1 LAST PATH I184
J 0
(-4650 425);
DISPLAY 0.872340 (-4650 425);
PAINT AQUA (-4650 425);
DISPLAY INVISIBLE (-4650 425);
FORCEPROP 1 LAST SIZE 1B
J 0
(-4650 375);
DISPLAY 0.872340 (-4650 375);
PAINT AQUA (-4650 375);
DISPLAY INVISIBLE (-4650 375);
FORCEPROP 1 LAST VOLTAGE 0.0V
J 0
(-4770 382);
DISPLAY 0.340426 (-4770 382);
PAINT SKYBLUE (-4770 382);
DISPLAY INVISIBLE (-4770 382);
FORCEADD P3V3_STBY..1
(-5175 1150);
FORCEPROP 3 LASTPIN (-5175 1100) SIG_NAME P3V3_STBY\g
J 0
(-5165 1110);
DISPLAY 0.659574 (-5165 1110);
PAINT MONO (-5165 1110);
DISPLAY INVISIBLE (-5165 1110);
FORCEPROP 1 LAST HDL_POWER P3V3_STBY
J 0
(-5475 1025);
DISPLAY 0.872340 (-5475 1025);
PAINT ORANGE (-5475 1025);
DISPLAY INVISIBLE (-5475 1025);
FORCEPROP 1 LAST BODY_TYPE PLUMBING
J 0
(-5220 1107);
DISPLAY 0.340426 (-5220 1107);
PAINT GREEN (-5220 1107);
DISPLAY INVISIBLE (-5220 1107);
FORCEPROP 1 LAST SIZE 1B
J 0
(-5130 1172);
DISPLAY 0.340426 (-5130 1172);
PAINT GREEN (-5130 1172);
DISPLAY INVISIBLE (-5130 1172);
FORCEPROP 1 LAST PATH I185
J 0
(-5130 1152);
DISPLAY 0.340426 (-5130 1152);
PAINT GREEN (-5130 1152);
DISPLAY INVISIBLE (-5130 1152);
FORCEPROP 2 LAST CDS_LIB mstr_symbols
J 0
(-5175 1150);
PAINT MONO (-5175 1150);
DISPLAY INVISIBLE (-5175 1150);
FORCEPROP 1 LAST VOLTAGE 3.3V
J 0
(-5220 1107);
DISPLAY 0.340426 (-5220 1107);
PAINT SKYBLUE (-5220 1107);
DISPLAY INVISIBLE (-5220 1107);
FORCEADD RES..2
(-5175 900);
FORCEPROP 1 LAST VALUE 4.75K
J 0
(-5130 975);
DISPLAY 0.617021 (-5130 975);
PAINT SKYBLUE (-5130 975);
FORCEPROP 1 LAST LOCATION R9A21
J 0
(-5130 1025);
DISPLAY 0.617021 (-5130 1025);
PAINT AQUA (-5130 1025);
FORCEPROP 1 LASTPIN (-5175 1000) $PN 1
J 0
(-5170 962);
DISPLAY 0.617021 (-5170 962);
PAINT ORANGE (-5170 962);
FORCEPROP 1 LAST WATTAGE 1/16W
J 0
(-5135 875);
DISPLAY 0.617021 (-5135 875);
PAINT SKYBLUE (-5135 875);
FORCEPROP 1 LAST PART_NUMBER G21796-072
J 0
(-5135 775);
DISPLAY 0.617021 (-5135 775);
PAINT BLUE (-5135 775);
FORCEPROP 1 LAST TOLERANCE 1%
J 0
(-5130 925);
DISPLAY 0.617021 (-5130 925);
PAINT SKYBLUE (-5130 925);
FORCEPROP 1 LAST PACK_TYPE 0402
J 0
(-5135 725);
DISPLAY 0.617021 (-5135 725);
PAINT SKYBLUE (-5135 725);
FORCEPROP 1 LAST MATERIAL CHIP
J 0
(-5135 825);
DISPLAY 0.617021 (-5135 825);
PAINT SKYBLUE (-5135 825);
FORCEPROP 1 LASTPIN (-5175 800) $PN 2
J 0
(-5170 810);
DISPLAY 0.617021 (-5170 810);
PAINT ORANGE (-5170 810);
FORCEPROP 0 LAST BOM_COST SB
J 0
(-5125 1225);
DISPLAY 1.021277 (-5125 1225);
PAINT ORANGE (-5125 1225);
DISPLAY INVISIBLE (-5125 1225);
FORCEPROP 0 LAST ROOM SB
J 0
(-5125 1125);
DISPLAY 1.021277 (-5125 1125);
PAINT ORANGE (-5125 1125);
DISPLAY INVISIBLE (-5125 1125);
FORCEPROP 1 LAST PATH I186
J 0
(-5125 1075);
DISPLAY 0.978723 (-5125 1075);
PAINT WHITE (-5125 1075);
DISPLAY INVISIBLE (-5125 1075);
FORCEPROP 2 LAST CDS_LOCATION R9A21
J 0
(-5130 1025);
DISPLAY 0.617021 (-5130 1025);
PAINT AQUA (-5130 1025);
DISPLAY INVISIBLE (-5130 1025);
FORCEPROP 2 LAST SEC 1
J 0
(-5125 1125);
DISPLAY 0.680851 (-5125 1125);
PAINT MONO (-5125 1125);
DISPLAY INVISIBLE (-5125 1125);
FORCEPROP 2 LAST SEC_TYPE 0402
J 0
(-5125 1125);
DISPLAY 1.021277 (-5125 1125);
PAINT ORANGE (-5125 1125);
DISPLAY INVISIBLE (-5125 1125);
FORCEPROP 2 LAST CDS_LIB mstr_discrete
J 0
(-5175 900);
PAINT MONO (-5175 900);
DISPLAY INVISIBLE (-5175 900);
FORCEADD OFFPAGE..2
(-775 2050);
FORCEPROP 2 LAST $XR0 119 
J 0
(-586 2050);
DISPLAY 0.638298 (-586 2050);
PAINT MONO (-586 2050);
FORCEPROP 1 LAST COMMENT_BODY TRUE
J 0
(-820 1955);
DISPLAY 1.404255 (-820 1955);
PAINT PEACH (-820 1955);
DISPLAY INVISIBLE (-820 1955);
FORCEPROP 1 LAST OFFPAGE TRUE
J 0
(-450 1925);
PAINT GREEN (-450 1925);
DISPLAY INVISIBLE (-450 1925);
FORCEPROP 2 LAST PATH I187
J 0
(-600 2125);
DISPLAY 1.021277 (-600 2125);
PAINT ORANGE (-600 2125);
DISPLAY INVISIBLE (-600 2125);
FORCEPROP 2 LAST CDS_LIB mstr_standard
J 0
(-775 2050);
PAINT MONO (-775 2050);
DISPLAY INVISIBLE (-775 2050);
FORCEADD OFFPAGE..2
(-775 2300);
FORCEPROP 2 LAST $XR2 190 
J 0
(-346 2300);
DISPLAY 0.638298 (-346 2300);
PAINT MONO (-346 2300);
FORCEPROP 2 LAST $XR1 157 
J 0
(-466 2300);
DISPLAY 0.638298 (-466 2300);
PAINT MONO (-466 2300);
FORCEPROP 2 LAST $XR0 145 
J 0
(-586 2300);
DISPLAY 0.638298 (-586 2300);
PAINT MONO (-586 2300);
FORCEPROP 1 LAST COMMENT_BODY TRUE
J 0
(-820 2205);
DISPLAY 1.404255 (-820 2205);
PAINT PEACH (-820 2205);
DISPLAY INVISIBLE (-820 2205);
FORCEPROP 1 LAST OFFPAGE TRUE
J 0
(-450 2175);
PAINT GREEN (-450 2175);
DISPLAY INVISIBLE (-450 2175);
FORCEPROP 2 LAST PATH I188
J 0
(-600 2375);
DISPLAY 1.021277 (-600 2375);
PAINT ORANGE (-600 2375);
DISPLAY INVISIBLE (-600 2375);
FORCEPROP 2 LAST CDS_LIB mstr_standard
J 0
(-775 2300);
PAINT MONO (-775 2300);
DISPLAY INVISIBLE (-775 2300);
FORCEADD RES..1
(-6750 3700);
FORCEPROP 1 LAST PACK_TYPE 0402
J 0
(-6475 3650);
DISPLAY 0.617021 (-6475 3650);
PAINT SKYBLUE (-6475 3650);
FORCEPROP 1 LAST LOCATION R7C26
J 0
(-6825 3750);
DISPLAY 0.617021 (-6825 3750);
PAINT AQUA (-6825 3750);
FORCEPROP 1 LASTPIN (-6650 3700) $PN 2
J 0
(-6688 3712);
DISPLAY 0.617021 (-6688 3712);
PAINT WHITE (-6688 3712);
FORCEPROP 1 LAST WATTAGE 1/16W
J 2
(-6600 3650);
DISPLAY 0.617021 (-6600 3650);
PAINT SKYBLUE (-6600 3650);
FORCEPROP 1 LAST PART_NUMBER G21796-074
J 0
(-6825 3600);
DISPLAY 0.617021 (-6825 3600);
PAINT BLUE (-6825 3600);
FORCEPROP 1 LASTPIN (-6850 3700) $PN 1
J 0
(-6838 3712);
DISPLAY 0.617021 (-6838 3712);
PAINT WHITE (-6838 3712);
FORCEPROP 1 LAST TOLERANCE 1%
J 0
(-6575 3650);
DISPLAY 0.617021 (-6575 3650);
PAINT SKYBLUE (-6575 3650);
FORCEPROP 1 LAST MATERIAL CHIP
J 0
(-6625 3700);
DISPLAY 0.617021 (-6625 3700);
PAINT SKYBLUE (-6625 3700);
FORCEPROP 1 LAST VALUE 33.2
J 2
(-6800 3650);
DISPLAY 0.617021 (-6800 3650);
PAINT SKYBLUE (-6800 3650);
FORCEPROP 2 LAST ROOM SYS_CLOCK
J 0
(-6800 3850);
DISPLAY 1.127660 (-6800 3850);
PAINT WHITE (-6800 3850);
DISPLAY INVISIBLE (-6800 3850);
FORCEPROP 1 LAST PATH I189
J 0
(-6800 3850);
DISPLAY 0.978723 (-6800 3850);
PAINT WHITE (-6800 3850);
DISPLAY INVISIBLE (-6800 3850);
FORCEPROP 2 LAST SEC_TYPE 0402
J 0
(-6800 3900);
DISPLAY 1.659574 (-6800 3900);
PAINT ORANGE (-6800 3900);
DISPLAY INVISIBLE (-6800 3900);
FORCEPROP 2 LAST SEC 1
J 0
(-6800 3900);
DISPLAY 1.510638 (-6800 3900);
PAINT MONO (-6800 3900);
DISPLAY INVISIBLE (-6800 3900);
FORCEPROP 2 LAST BOM_COST SM_CONTROLLER
J 0
(-6800 3825);
DISPLAY 1.617021 (-6800 3825);
PAINT WHITE (-6800 3825);
DISPLAY INVISIBLE (-6800 3825);
FORCEPROP 2 LAST CDS_LIB mstr_discrete
J 0
(-6750 3700);
DISPLAY 1.617021 (-6750 3700);
PAINT ORANGE (-6750 3700);
DISPLAY INVISIBLE (-6750 3700);
FORCEPROP 2 LAST CDS_LOCATION R7C26
J 0
(-6950 3700);
DISPLAY 0.617021 (-6950 3700);
PAINT AQUA (-6950 3700);
DISPLAY INVISIBLE (-6950 3700);
FORCEADD OFFPAGE..5
(-7550 3700);
FORCEPROP 2 LAST $XR0 146 
J 0
(-7805 3700);
DISPLAY 0.638298 (-7805 3700);
PAINT MONO (-7805 3700);
FORCEPROP 2 LAST PATH I190
J 0
(-7825 3750);
DISPLAY 1.021277 (-7825 3750);
PAINT ORANGE (-7825 3750);
DISPLAY INVISIBLE (-7825 3750);
FORCEPROP 2 LAST CDS_LIB mstr_standard
J 0
(-7550 3700);
PAINT ORANGE (-7550 3700);
DISPLAY INVISIBLE (-7550 3700);
FORCEPROP 1 LAST OFFPAGE TRUE
J 0
(-7225 3575);
DISPLAY 0.872340 (-7225 3575);
PAINT GREEN (-7225 3575);
DISPLAY INVISIBLE (-7225 3575);
FORCEPROP 1 LAST COMMENT_BODY TRUE
J 0
(-7450 3625);
DISPLAY 0.872340 (-7450 3625);
PAINT GREEN (-7450 3625);
DISPLAY INVISIBLE (-7450 3625);
FORCEADD OFFPAGE..4
R 2
(-7175 2450);
FORCEPROP 2 LAST $XR2 190 
J 0
(-7667 2450);
DISPLAY 0.638298 (-7667 2450);
PAINT MONO (-7667 2450);
FORCEPROP 2 LAST $XR1 145 
J 0
(-7547 2450);
DISPLAY 0.638298 (-7547 2450);
PAINT MONO (-7547 2450);
FORCEPROP 2 LAST $XR0 175 
J 0
(-7427 2450);
DISPLAY 0.638298 (-7427 2450);
PAINT MONO (-7427 2450);
FORCEPROP 1 LAST COMMENT_BODY TRUE
J 2
(-7150 2350);
DISPLAY 0.872340 (-7150 2350);
PAINT GREEN (-7150 2350);
DISPLAY INVISIBLE (-7150 2350);
FORCEPROP 1 LAST OFFPAGE TRUE
J 2
(-7500 2325);
DISPLAY 0.872340 (-7500 2325);
PAINT GREEN (-7500 2325);
DISPLAY INVISIBLE (-7500 2325);
FORCEPROP 2 LAST PATH I196
J 0
(-7125 2525);
DISPLAY 1.021277 (-7125 2525);
PAINT ORANGE (-7125 2525);
DISPLAY INVISIBLE (-7125 2525);
FORCEPROP 2 LAST CDS_LIB mstr_standard
J 0
(-7175 2450);
PAINT ORANGE (-7175 2450);
DISPLAY INVISIBLE (-7175 2450);
FORCEADD OFFPAGE..4
R 2
(-7175 2400);
FORCEPROP 2 LAST $XR1 145 
J 0
(-7547 2400);
DISPLAY 0.638298 (-7547 2400);
PAINT MONO (-7547 2400);
FORCEPROP 2 LAST $XR0 157 
J 0
(-7427 2400);
DISPLAY 0.638298 (-7427 2400);
PAINT MONO (-7427 2400);
FORCEPROP 1 LAST COMMENT_BODY TRUE
J 2
(-7150 2300);
DISPLAY 0.872340 (-7150 2300);
PAINT GREEN (-7150 2300);
DISPLAY INVISIBLE (-7150 2300);
FORCEPROP 1 LAST OFFPAGE TRUE
J 2
(-7500 2275);
DISPLAY 0.872340 (-7500 2275);
PAINT GREEN (-7500 2275);
DISPLAY INVISIBLE (-7500 2275);
FORCEPROP 2 LAST PATH I197
J 0
(-7125 2475);
DISPLAY 1.021277 (-7125 2475);
PAINT ORANGE (-7125 2475);
DISPLAY INVISIBLE (-7125 2475);
FORCEPROP 2 LAST CDS_LIB mstr_standard
J 0
(-7175 2400);
PAINT ORANGE (-7175 2400);
DISPLAY INVISIBLE (-7175 2400);
FORCEADD OFFPAGE..1
(-7750 2500);
FORCEPROP 2 LAST CDS_LIB mstr_standard
J 0
(-7750 2500);
PAINT ORANGE (-7750 2500);
DISPLAY INVISIBLE (-7750 2500);
FORCEPROP 2 LAST PATH I198
J 0
(-7700 2575);
DISPLAY 1.021277 (-7700 2575);
PAINT ORANGE (-7700 2575);
DISPLAY INVISIBLE (-7700 2575);
FORCEPROP 1 LAST OFFPAGE TRUE
J 0
(-7425 2375);
DISPLAY 0.872340 (-7425 2375);
PAINT GREEN (-7425 2375);
DISPLAY INVISIBLE (-7425 2375);
FORCEPROP 1 LAST COMMENT_BODY TRUE
J 0
(-7625 2400);
DISPLAY 0.872340 (-7625 2400);
PAINT GREEN (-7625 2400);
DISPLAY INVISIBLE (-7625 2400);
FORCEPROP 2 LAST $XR1 145 
J 0
(-8176 2500);
DISPLAY 0.638298 (-8176 2500);
PAINT MONO (-8176 2500);
DISPLAY INVISIBLE (-8176 2500);
FORCEPROP 2 LAST $XR0 175 
J 0
(-8176 2500);
DISPLAY 0.638298 (-8176 2500);
PAINT MONO (-8176 2500);
DISPLAY INVISIBLE (-8176 2500);
FORCEADD OFFPAGE..4
R 2
(-7375 3250);
FORCEPROP 2 LAST $XR0 133 
J 0
(-7627 3250);
DISPLAY 0.638298 (-7627 3250);
PAINT MONO (-7627 3250);
FORCEPROP 1 LAST COMMENT_BODY TRUE
J 2
(-7350 3150);
DISPLAY 0.872340 (-7350 3150);
PAINT GREEN (-7350 3150);
DISPLAY INVISIBLE (-7350 3150);
FORCEPROP 1 LAST OFFPAGE TRUE
J 2
(-7700 3125);
DISPLAY 0.872340 (-7700 3125);
PAINT GREEN (-7700 3125);
DISPLAY INVISIBLE (-7700 3125);
FORCEPROP 2 LAST CDS_LIB mstr_standard
J 2
(-7375 3250);
PAINT ORANGE (-7375 3250);
DISPLAY INVISIBLE (-7375 3250);
FORCEPROP 2 LAST PATH I2
J 2
(-7425 3325);
DISPLAY 1.021277 (-7425 3325);
PAINT ORANGE (-7425 3325);
DISPLAY INVISIBLE (-7425 3325);
FORCEADD OFFPAGE..1
(-7175 2800);
FORCEPROP 2 LAST $XR2 145 
J 0
(-7697 2800);
DISPLAY 0.638298 (-7697 2800);
PAINT MONO (-7697 2800);
FORCEPROP 2 LAST $XR1 133 
J 0
(-7577 2800);
DISPLAY 0.638298 (-7577 2800);
PAINT MONO (-7577 2800);
FORCEPROP 2 LAST $XR0 120 
J 0
(-7457 2800);
DISPLAY 0.638298 (-7457 2800);
PAINT MONO (-7457 2800);
FORCEPROP 1 LAST COMMENT_BODY TRUE
J 0
(-7050 2700);
DISPLAY 0.872340 (-7050 2700);
PAINT GREEN (-7050 2700);
DISPLAY INVISIBLE (-7050 2700);
FORCEPROP 1 LAST OFFPAGE TRUE
J 0
(-6850 2675);
DISPLAY 0.872340 (-6850 2675);
PAINT GREEN (-6850 2675);
DISPLAY INVISIBLE (-6850 2675);
FORCEPROP 2 LAST PATH I202
J 0
(-7125 2875);
DISPLAY 1.021277 (-7125 2875);
PAINT ORANGE (-7125 2875);
DISPLAY INVISIBLE (-7125 2875);
FORCEPROP 2 LAST CDS_LIB mstr_standard
J 0
(-7175 2800);
PAINT ORANGE (-7175 2800);
DISPLAY INVISIBLE (-7175 2800);
FORCEADD OFFPAGE..4
R 2
(-7175 2750);
FORCEPROP 2 LAST $XR1 190 
J 0
(-7547 2750);
DISPLAY 0.638298 (-7547 2750);
PAINT MONO (-7547 2750);
FORCEPROP 2 LAST $XR0 183 
J 0
(-7427 2750);
DISPLAY 0.638298 (-7427 2750);
PAINT MONO (-7427 2750);
FORCEPROP 1 LAST COMMENT_BODY TRUE
J 2
(-7150 2650);
DISPLAY 0.872340 (-7150 2650);
PAINT GREEN (-7150 2650);
DISPLAY INVISIBLE (-7150 2650);
FORCEPROP 1 LAST OFFPAGE TRUE
J 2
(-7500 2625);
DISPLAY 0.872340 (-7500 2625);
PAINT GREEN (-7500 2625);
DISPLAY INVISIBLE (-7500 2625);
FORCEPROP 2 LAST PATH I203
J 0
(-7125 2825);
DISPLAY 1.021277 (-7125 2825);
PAINT ORANGE (-7125 2825);
DISPLAY INVISIBLE (-7125 2825);
FORCEPROP 2 LAST CDS_LIB mstr_standard
J 0
(-7175 2750);
PAINT ORANGE (-7175 2750);
DISPLAY INVISIBLE (-7175 2750);
FORCEADD OFFPAGE..1
(-7550 4350);
FORCEPROP 2 LAST $XR2 146 
J 0
(-8102 4386);
DISPLAY 0.638298 (-8102 4386);
PAINT MONO (-8102 4386);
FORCEPROP 2 LAST $XR1 249 
J 0
(-8102 4314);
DISPLAY 0.638298 (-8102 4314);
PAINT MONO (-8102 4314);
FORCEPROP 2 LAST $XR0 133 
J 0
(-8102 4350);
DISPLAY 0.638298 (-8102 4350);
PAINT MONO (-8102 4350);
FORCEPROP 2 LAST PATH I205
J 0
(-7800 4400);
DISPLAY 1.021277 (-7800 4400);
PAINT ORANGE (-7800 4400);
DISPLAY INVISIBLE (-7800 4400);
FORCEPROP 2 LAST CDS_LIB mstr_standard
J 0
(-7550 4350);
PAINT ORANGE (-7550 4350);
DISPLAY INVISIBLE (-7550 4350);
FORCEPROP 1 LAST OFFPAGE TRUE
J 0
(-7225 4225);
DISPLAY 0.872340 (-7225 4225);
PAINT GREEN (-7225 4225);
DISPLAY INVISIBLE (-7225 4225);
FORCEPROP 1 LAST COMMENT_BODY TRUE
J 0
(-7425 4250);
DISPLAY 0.872340 (-7425 4250);
PAINT GREEN (-7425 4250);
DISPLAY INVISIBLE (-7425 4250);
FORCEADD OFFPAGE..5
(-7750 2600);
FORCEPROP 1 LAST COMMENT_BODY TRUE
J 0
(-7650 2525);
DISPLAY 0.872340 (-7650 2525);
PAINT GREEN (-7650 2525);
DISPLAY INVISIBLE (-7650 2525);
FORCEPROP 1 LAST OFFPAGE TRUE
J 0
(-7425 2475);
DISPLAY 0.872340 (-7425 2475);
PAINT GREEN (-7425 2475);
DISPLAY INVISIBLE (-7425 2475);
FORCEPROP 2 LAST CDS_LIB mstr_standard
J 0
(-7750 2600);
PAINT ORANGE (-7750 2600);
DISPLAY INVISIBLE (-7750 2600);
FORCEPROP 2 LAST PATH I208
J 0
(-8025 2650);
DISPLAY 1.021277 (-8025 2650);
PAINT ORANGE (-8025 2650);
DISPLAY INVISIBLE (-8025 2650);
FORCEPROP 2 LAST $XR1 190 
J 0
(-8179 2600);
DISPLAY 0.638298 (-8179 2600);
PAINT MONO (-8179 2600);
DISPLAY INVISIBLE (-8179 2600);
FORCEPROP 2 LAST $XR0 147 
J 0
(-8179 2600);
DISPLAY 0.638298 (-8179 2600);
PAINT MONO (-8179 2600);
DISPLAY INVISIBLE (-8179 2600);
FORCEADD OFFPAGE..5
(-7550 4100);
FORCEPROP 2 LAST $XR1 156 
J 0
(-7925 4100);
DISPLAY 0.638298 (-7925 4100);
PAINT MONO (-7925 4100);
FORCEPROP 2 LAST $XR0 164 
J 0
(-7805 4100);
DISPLAY 0.638298 (-7805 4100);
PAINT MONO (-7805 4100);
FORCEPROP 2 LAST CDS_LIB mstr_standard
J 0
(-7550 4100);
PAINT ORANGE (-7550 4100);
DISPLAY INVISIBLE (-7550 4100);
FORCEPROP 2 LAST PATH I209
J 0
(-7500 4175);
DISPLAY 1.021277 (-7500 4175);
PAINT ORANGE (-7500 4175);
DISPLAY INVISIBLE (-7500 4175);
FORCEPROP 1 LAST OFFPAGE TRUE
J 0
(-7225 3975);
DISPLAY 0.872340 (-7225 3975);
PAINT GREEN (-7225 3975);
DISPLAY INVISIBLE (-7225 3975);
FORCEPROP 1 LAST COMMENT_BODY TRUE
J 0
(-7450 4025);
DISPLAY 0.872340 (-7450 4025);
PAINT GREEN (-7450 4025);
DISPLAY INVISIBLE (-7450 4025);
FORCEADD OFFPAGE..4
R 2
(-7550 4200);
FORCEPROP 2 LAST $XR0 136 
J 0
(-7802 4200);
DISPLAY 0.638298 (-7802 4200);
PAINT MONO (-7802 4200);
FORCEPROP 2 LAST CDS_LIB mstr_standard
J 0
(-7550 4200);
PAINT ORANGE (-7550 4200);
DISPLAY INVISIBLE (-7550 4200);
FORCEPROP 2 LAST PATH I21
J 0
(-7500 4275);
DISPLAY 1.021277 (-7500 4275);
PAINT ORANGE (-7500 4275);
DISPLAY INVISIBLE (-7500 4275);
FORCEPROP 1 LAST OFFPAGE TRUE
J 2
(-7875 4075);
DISPLAY 0.872340 (-7875 4075);
PAINT GREEN (-7875 4075);
DISPLAY INVISIBLE (-7875 4075);
FORCEPROP 1 LAST COMMENT_BODY TRUE
J 2
(-7525 4100);
DISPLAY 0.872340 (-7525 4100);
PAINT GREEN (-7525 4100);
DISPLAY INVISIBLE (-7525 4100);
FORCEADD OFFPAGE..5
(-7175 2850);
FORCEPROP 2 LAST $XR0 156 
J 0
(-7460 2850);
DISPLAY 0.638298 (-7460 2850);
PAINT MONO (-7460 2850);
FORCEPROP 1 LAST COMMENT_BODY TRUE
J 0
(-7075 2775);
DISPLAY 1.404255 (-7075 2775);
PAINT PEACH (-7075 2775);
DISPLAY INVISIBLE (-7075 2775);
FORCEPROP 1 LAST OFFPAGE TRUE
J 0
(-6850 2725);
PAINT GREEN (-6850 2725);
DISPLAY INVISIBLE (-6850 2725);
FORCEPROP 2 LAST CDS_LIB mstr_standard
J 0
(-7175 2850);
PAINT ORANGE (-7175 2850);
DISPLAY INVISIBLE (-7175 2850);
FORCEPROP 2 LAST PATH I211
J 0
(-7450 2900);
DISPLAY 1.021277 (-7450 2900);
PAINT ORANGE (-7450 2900);
DISPLAY INVISIBLE (-7450 2900);
FORCEADD OFFPAGE..5
(-7175 3100);
FORCEPROP 2 LAST $XR1 176 
J 0
(-7580 3100);
DISPLAY 0.638298 (-7580 3100);
PAINT MONO (-7580 3100);
FORCEPROP 2 LAST $XR0 125 
J 0
(-7460 3100);
DISPLAY 0.638298 (-7460 3100);
PAINT MONO (-7460 3100);
FORCEPROP 1 LAST COMMENT_BODY TRUE
J 0
(-7075 3025);
DISPLAY 1.404255 (-7075 3025);
PAINT PEACH (-7075 3025);
DISPLAY INVISIBLE (-7075 3025);
FORCEPROP 1 LAST OFFPAGE TRUE
J 0
(-6850 2975);
PAINT GREEN (-6850 2975);
DISPLAY INVISIBLE (-6850 2975);
FORCEPROP 2 LAST CDS_LIB mstr_standard
J 0
(-7175 3100);
PAINT ORANGE (-7175 3100);
DISPLAY INVISIBLE (-7175 3100);
FORCEPROP 2 LAST PATH I212
J 0
(-7450 3150);
DISPLAY 1.021277 (-7450 3150);
PAINT ORANGE (-7450 3150);
DISPLAY INVISIBLE (-7450 3150);
FORCEADD RES..2
(-1700 4725);
FORCEPROP 1 LAST MATERIAL CHIP
J 0
(-1660 4650);
DISPLAY 0.617021 (-1660 4650);
PAINT SKYBLUE (-1660 4650);
FORCEPROP 1 LAST PART_NUMBER G21796-072
J 0
(-1660 4600);
DISPLAY 0.617021 (-1660 4600);
PAINT BLUE (-1660 4600);
FORCEPROP 1 LAST PACK_TYPE 0402
J 0
(-1660 4550);
DISPLAY 0.617021 (-1660 4550);
PAINT SKYBLUE (-1660 4550);
FORCEPROP 1 LAST TOLERANCE 1%
J 0
(-1655 4750);
DISPLAY 0.617021 (-1655 4750);
PAINT SKYBLUE (-1655 4750);
FORCEPROP 1 LAST LOCATION R2U48
J 0
(-1655 4850);
DISPLAY 0.617021 (-1655 4850);
PAINT AQUA (-1655 4850);
FORCEPROP 1 LAST VALUE 4.75K
J 0
(-1655 4800);
DISPLAY 0.617021 (-1655 4800);
PAINT SKYBLUE (-1655 4800);
FORCEPROP 1 LAST WATTAGE 1/16W
J 0
(-1660 4700);
DISPLAY 0.617021 (-1660 4700);
PAINT SKYBLUE (-1660 4700);
FORCEPROP 1 LASTPIN (-1700 4825) $PN 1
J 0
(-1695 4787);
DISPLAY 0.617021 (-1695 4787);
PAINT ORANGE (-1695 4787);
FORCEPROP 1 LASTPIN (-1700 4625) $PN 2
J 0
(-1695 4635);
DISPLAY 0.617021 (-1695 4635);
PAINT ORANGE (-1695 4635);
FORCEPROP 1 LAST PATH I213
J 0
(-1650 4900);
DISPLAY 0.978723 (-1650 4900);
PAINT WHITE (-1650 4900);
DISPLAY INVISIBLE (-1650 4900);
FORCEPROP 2 LAST SEC 1
J 0
(-1650 4950);
DISPLAY 0.680851 (-1650 4950);
PAINT MONO (-1650 4950);
DISPLAY INVISIBLE (-1650 4950);
FORCEPROP 2 LAST SEC_TYPE 0402
J 0
(-1650 4950);
DISPLAY 1.021277 (-1650 4950);
PAINT ORANGE (-1650 4950);
DISPLAY INVISIBLE (-1650 4950);
FORCEPROP 2 LAST CDS_LIB mstr_discrete
J 0
(-1700 4725);
PAINT ORANGE (-1700 4725);
DISPLAY INVISIBLE (-1700 4725);
FORCEADD P3V3_STBY..1
(-1700 4900);
FORCEPROP 3 LASTPIN (-1700 4850) SIG_NAME P3V3_STBY\g
J 0
(-1690 4860);
DISPLAY 0.659574 (-1690 4860);
PAINT MONO (-1690 4860);
DISPLAY INVISIBLE (-1690 4860);
FORCEPROP 1 LAST HDL_POWER P3V3_STBY
J 0
(-2000 4775);
DISPLAY 0.872340 (-2000 4775);
PAINT ORANGE (-2000 4775);
DISPLAY INVISIBLE (-2000 4775);
FORCEPROP 1 LAST BODY_TYPE PLUMBING
J 0
(-1745 4857);
DISPLAY 0.340426 (-1745 4857);
PAINT GREEN (-1745 4857);
DISPLAY INVISIBLE (-1745 4857);
FORCEPROP 1 LAST PATH I214
J 0
(-1655 4902);
DISPLAY 0.340426 (-1655 4902);
PAINT GREEN (-1655 4902);
DISPLAY INVISIBLE (-1655 4902);
FORCEPROP 2 LAST CDS_LIB mstr_symbols
J 0
(-1700 4900);
PAINT ORANGE (-1700 4900);
DISPLAY INVISIBLE (-1700 4900);
FORCEPROP 1 LAST SIZE 1B
J 0
(-1655 4922);
DISPLAY 0.340426 (-1655 4922);
PAINT GREEN (-1655 4922);
DISPLAY INVISIBLE (-1655 4922);
FORCEPROP 1 LAST VOLTAGE 3.3V
J 0
(-1745 4857);
DISPLAY 0.340426 (-1745 4857);
PAINT SKYBLUE (-1745 4857);
DISPLAY INVISIBLE (-1745 4857);
FORCEADD OFFPAGE..4
(-400 4100);
FORCEPROP 2 LAST $XR0 108 
J 0
(-214 4100);
DISPLAY 0.638298 (-214 4100);
PAINT MONO (-214 4100);
FORCEPROP 1 LAST COMMENT_BODY TRUE
J 0
(-425 4000);
DISPLAY 1.404255 (-425 4000);
PAINT PEACH (-425 4000);
DISPLAY INVISIBLE (-425 4000);
FORCEPROP 1 LAST OFFPAGE TRUE
J 0
(-75 3975);
PAINT GREEN (-75 3975);
DISPLAY INVISIBLE (-75 3975);
FORCEPROP 2 LAST PATH I216
J 0
(-225 4175);
DISPLAY 1.021277 (-225 4175);
PAINT ORANGE (-225 4175);
DISPLAY INVISIBLE (-225 4175);
FORCEPROP 2 LAST CDS_LIB mstr_standard
J 0
(-400 4100);
PAINT ORANGE (-400 4100);
DISPLAY INVISIBLE (-400 4100);
FORCEADD OFFPAGE..2
(-775 3700);
FORCEPROP 2 LAST $XR1 190 
J 0
(-466 3700);
DISPLAY 0.638298 (-466 3700);
PAINT MONO (-466 3700);
FORCEPROP 2 LAST $XR0 133 
J 0
(-586 3700);
DISPLAY 0.638298 (-586 3700);
PAINT MONO (-586 3700);
FORCEPROP 1 LAST COMMENT_BODY TRUE
J 0
(-820 3605);
DISPLAY 0.872340 (-820 3605);
PAINT GREEN (-820 3605);
DISPLAY INVISIBLE (-820 3605);
FORCEPROP 1 LAST OFFPAGE TRUE
J 0
(-450 3575);
DISPLAY 0.872340 (-450 3575);
PAINT ORANGE (-450 3575);
DISPLAY INVISIBLE (-450 3575);
FORCEPROP 2 LAST CDS_LIB mstr_standard
J 0
(-775 3700);
PAINT ORANGE (-775 3700);
DISPLAY INVISIBLE (-775 3700);
FORCEPROP 2 LAST PATH I217
J 0
(-1050 3750);
DISPLAY 1.021277 (-1050 3750);
PAINT ORANGE (-1050 3750);
DISPLAY INVISIBLE (-1050 3750);
FORCEADD OFFPAGE..5
(-7550 4150);
FORCEPROP 2 LAST $XR0 156 
J 0
(-7805 4150);
DISPLAY 0.638298 (-7805 4150);
PAINT MONO (-7805 4150);
FORCEPROP 2 LAST PATH I218
J 0
(-7825 4200);
DISPLAY 1.021277 (-7825 4200);
PAINT ORANGE (-7825 4200);
DISPLAY INVISIBLE (-7825 4200);
FORCEPROP 2 LAST CDS_LIB mstr_standard
J 0
(-7550 4150);
PAINT ORANGE (-7550 4150);
DISPLAY INVISIBLE (-7550 4150);
FORCEPROP 1 LAST OFFPAGE TRUE
J 0
(-7225 4025);
PAINT GREEN (-7225 4025);
DISPLAY INVISIBLE (-7225 4025);
FORCEPROP 1 LAST COMMENT_BODY TRUE
J 0
(-7450 4075);
DISPLAY 1.404255 (-7450 4075);
PAINT PEACH (-7450 4075);
DISPLAY INVISIBLE (-7450 4075);
FORCEADD OFFPAGE..3
(-775 2700);
FORCEPROP 2 LAST $XR1 138 
J 0
(-351 2700);
DISPLAY 0.638298 (-351 2700);
PAINT MONO (-351 2700);
FORCEPROP 2 LAST $XR0 108 
J 0
(-471 2700);
DISPLAY 0.638298 (-471 2700);
PAINT MONO (-471 2700);
FORCEPROP 1 LAST COMMENT_BODY TRUE
J 0
(-825 2600);
DISPLAY 1.404255 (-825 2600);
PAINT PEACH (-825 2600);
DISPLAY INVISIBLE (-825 2600);
FORCEPROP 1 LAST OFFPAGE TRUE
J 0
(-450 2575);
PAINT GREEN (-450 2575);
DISPLAY INVISIBLE (-450 2575);
FORCEPROP 2 LAST CDS_LIB mstr_standard
J 0
(-775 2700);
PAINT MONO (-775 2700);
DISPLAY INVISIBLE (-775 2700);
FORCEPROP 2 LAST PATH I219
J 0
(-575 2775);
DISPLAY 1.021277 (-575 2775);
PAINT ORANGE (-575 2775);
DISPLAY INVISIBLE (-575 2775);
FORCEADD OFFPAGE..5
(-7175 3000);
FORCEPROP 2 LAST $XR2 146 
J 0
(-7700 3000);
DISPLAY 0.638298 (-7700 3000);
PAINT MONO (-7700 3000);
FORCEPROP 2 LAST $XR1 119 
J 0
(-7580 3000);
DISPLAY 0.638298 (-7580 3000);
PAINT MONO (-7580 3000);
FORCEPROP 2 LAST $XR0 133 
J 0
(-7460 3000);
DISPLAY 0.638298 (-7460 3000);
PAINT MONO (-7460 3000);
FORCEPROP 1 LAST COMMENT_BODY TRUE
J 0
(-7075 2925);
DISPLAY 1.404255 (-7075 2925);
PAINT PEACH (-7075 2925);
DISPLAY INVISIBLE (-7075 2925);
FORCEPROP 1 LAST OFFPAGE TRUE
J 0
(-6850 2875);
PAINT GREEN (-6850 2875);
DISPLAY INVISIBLE (-6850 2875);
FORCEPROP 2 LAST PATH I22
J 0
(-7125 3075);
DISPLAY 1.021277 (-7125 3075);
PAINT ORANGE (-7125 3075);
DISPLAY INVISIBLE (-7125 3075);
FORCEPROP 2 LAST CDS_LIB mstr_standard
J 0
(-7175 3000);
PAINT ORANGE (-7175 3000);
DISPLAY INVISIBLE (-7175 3000);
FORCEADD OFFPAGE..2
(-775 2650);
FORCEPROP 2 LAST $XR1 108 
J 0
(-346 2650);
DISPLAY 0.638298 (-346 2650);
PAINT MONO (-346 2650);
FORCEPROP 2 LAST $XR0 138 
J 0
(-466 2650);
DISPLAY 0.638298 (-466 2650);
PAINT MONO (-466 2650);
FORCEPROP 1 LAST COMMENT_BODY TRUE
J 0
(-820 2555);
DISPLAY 0.872340 (-820 2555);
PAINT GREEN (-820 2555);
DISPLAY INVISIBLE (-820 2555);
FORCEPROP 1 LAST OFFPAGE TRUE
J 0
(-450 2525);
DISPLAY 0.872340 (-450 2525);
PAINT GREEN (-450 2525);
DISPLAY INVISIBLE (-450 2525);
FORCEPROP 2 LAST PATH I220
J 0
(-600 2725);
DISPLAY 1.021277 (-600 2725);
PAINT ORANGE (-600 2725);
DISPLAY INVISIBLE (-600 2725);
FORCEPROP 2 LAST CDS_LIB mstr_standard
J 0
(-775 2650);
PAINT MONO (-775 2650);
DISPLAY INVISIBLE (-775 2650);
FORCEADD OFFPAGE..4
(-775 2800);
FORCEPROP 2 LAST $XR2 145 
J 0
(-319 2800);
DISPLAY 0.638298 (-319 2800);
PAINT MONO (-319 2800);
FORCEPROP 2 LAST $XR1 157 
J 0
(-439 2800);
DISPLAY 0.638298 (-439 2800);
PAINT MONO (-439 2800);
FORCEPROP 2 LAST $XR0 108 
J 0
(-559 2800);
DISPLAY 0.638298 (-559 2800);
PAINT MONO (-559 2800);
FORCEPROP 1 LAST COMMENT_BODY TRUE
J 0
(-800 2700);
DISPLAY 1.404255 (-800 2700);
PAINT PEACH (-800 2700);
DISPLAY INVISIBLE (-800 2700);
FORCEPROP 1 LAST OFFPAGE TRUE
J 0
(-450 2675);
PAINT GREEN (-450 2675);
DISPLAY INVISIBLE (-450 2675);
FORCEPROP 2 LAST CDS_LIB mstr_standard
J 0
(-775 2800);
PAINT MONO (-775 2800);
DISPLAY INVISIBLE (-775 2800);
FORCEPROP 2 LAST PATH I221
J 0
(-325 2850);
DISPLAY 1.021277 (-325 2850);
PAINT ORANGE (-325 2850);
DISPLAY INVISIBLE (-325 2850);
FORCEADD OFFPAGE..2
(-775 2600);
FORCEPROP 2 LAST $XR2 249 
J 0
(-316 2600);
DISPLAY 0.638298 (-316 2600);
PAINT MONO (-316 2600);
FORCEPROP 2 LAST $XR1 184 
J 0
(-436 2600);
DISPLAY 0.638298 (-436 2600);
PAINT MONO (-436 2600);
FORCEPROP 2 LAST $XR0 157 
J 0
(-556 2600);
DISPLAY 0.638298 (-556 2600);
PAINT MONO (-556 2600);
FORCEPROP 1 LAST COMMENT_BODY TRUE
J 0
(-820 2505);
DISPLAY 0.872340 (-820 2505);
PAINT GREEN (-820 2505);
DISPLAY INVISIBLE (-820 2505);
FORCEPROP 1 LAST OFFPAGE TRUE
J 0
(-450 2475);
DISPLAY 0.872340 (-450 2475);
PAINT GREEN (-450 2475);
DISPLAY INVISIBLE (-450 2475);
FORCEPROP 2 LAST CDS_LIB mstr_standard
J 0
(-775 2600);
PAINT MONO (-775 2600);
DISPLAY INVISIBLE (-775 2600);
FORCEPROP 2 LAST PATH I222
J 0
(-600 2675);
DISPLAY 1.021277 (-600 2675);
PAINT ORANGE (-600 2675);
DISPLAY INVISIBLE (-600 2675);
FORCEADD RES..1
(-1200 4150);
FORCEPROP 1 LAST TOLERANCE 5%
J 0
(-1100 4100);
DISPLAY 0.617021 (-1100 4100);
PAINT SKYBLUE (-1100 4100);
FORCEPROP 1 LAST PART_NUMBER G21497-005
J 0
(-1300 3950);
DISPLAY 0.617021 (-1300 3950);
PAINT BLUE (-1300 3950);
FORCEPROP 1 LASTPIN (-1300 4150) $PN 1
J 0
(-1288 4162);
DISPLAY 0.617021 (-1288 4162);
PAINT WHITE (-1288 4162);
FORCEPROP 1 LAST LOCATION R2W3
J 0
(-1300 4100);
DISPLAY 0.617021 (-1300 4100);
PAINT AQUA (-1300 4100);
FORCEPROP 1 LAST VALUE 0.0
J 0
(-1175 4100);
DISPLAY 0.617021 (-1175 4100);
PAINT SKYBLUE (-1175 4100);
FORCEPROP 1 LAST PACK_TYPE 0402
J 0
(-1300 4000);
DISPLAY 0.617021 (-1300 4000);
PAINT SKYBLUE (-1300 4000);
FORCEPROP 1 LAST WATTAGE 1/16W
J 0
(-1200 4000);
DISPLAY 0.638298 (-1200 4000);
PAINT SKYBLUE (-1200 4000);
FORCEPROP 1 LASTPIN (-1100 4150) $PN 2
J 0
(-1138 4162);
DISPLAY 0.617021 (-1138 4162);
PAINT WHITE (-1138 4162);
FORCEPROP 2 LAST SEC 1
J 0
(-1250 4375);
DISPLAY 0.680851 (-1250 4375);
PAINT MONO (-1250 4375);
DISPLAY INVISIBLE (-1250 4375);
FORCEPROP 2 LAST SEC_TYPE 0402
J 0
(-1250 4375);
DISPLAY 1.021277 (-1250 4375);
PAINT ORANGE (-1250 4375);
DISPLAY INVISIBLE (-1250 4375);
FORCEPROP 2 LAST ROOM CPU0
J 0
(-1250 4300);
PAINT PEACH (-1250 4300);
DISPLAY INVISIBLE (-1250 4300);
FORCEPROP 1 LAST MATERIAL CHIP
J 0
(-1050 4050);
DISPLAY 0.510638 (-1050 4050);
PAINT SKYBLUE (-1050 4050);
DISPLAY INVISIBLE (-1050 4050);
FORCEPROP 2 LAST BOM_COST PROC_SIDEBAND
J 0
(-1200 4150);
PAINT MONO (-1200 4150);
DISPLAY INVISIBLE (-1200 4150);
FORCEPROP 2 LAST CDS_LIB mstr_discrete
J 0
(-1200 4150);
DISPLAY 1.340426 (-1200 4150);
PAINT ORANGE (-1200 4150);
DISPLAY INVISIBLE (-1200 4150);
FORCEPROP 2 LAST CDS_LOCATION R2W3
J 0
(-1675 4150);
DISPLAY 0.617021 (-1675 4150);
PAINT AQUA (-1675 4150);
DISPLAY INVISIBLE (-1675 4150);
FORCEPROP 1 LAST PATH I223
J 0
(-1250 4300);
DISPLAY 0.978723 (-1250 4300);
PAINT WHITE (-1250 4300);
DISPLAY INVISIBLE (-1250 4300);
FORCEADD RES..1
(-6925 2550);
FORCEPROP 1 LAST LOCATION R2W4
J 0
(-7075 2650);
DISPLAY 0.617021 (-7075 2650);
PAINT AQUA (-7075 2650);
FORCEPROP 1 LASTPIN (-6825 2550) $PN 2
J 0
(-6863 2562);
DISPLAY 0.617021 (-6863 2562);
PAINT WHITE (-6863 2562);
FORCEPROP 1 LAST VALUE 0.0
J 0
(-7100 2600);
DISPLAY 0.617021 (-7100 2600);
PAINT SKYBLUE (-7100 2600);
FORCEPROP 1 LAST PACK_TYPE 0402
J 0
(-6950 2600);
DISPLAY 0.617021 (-6950 2600);
PAINT SKYBLUE (-6950 2600);
FORCEPROP 1 LAST WATTAGE 1/16W
J 0
(-6825 2600);
DISPLAY 0.510638 (-6825 2600);
PAINT SKYBLUE (-6825 2600);
FORCEPROP 1 LASTPIN (-7025 2550) $PN 1
J 0
(-7013 2562);
DISPLAY 0.617021 (-7013 2562);
PAINT WHITE (-7013 2562);
FORCEPROP 1 LAST TOLERANCE 5%
J 0
(-7025 2600);
DISPLAY 0.617021 (-7025 2600);
PAINT SKYBLUE (-7025 2600);
FORCEPROP 1 LAST PART_NUMBER G21497-005
J 0
(-6950 2650);
DISPLAY 0.617021 (-6950 2650);
PAINT BLUE (-6950 2650);
FORCEPROP 0 LAST POP NOPOP
J 0
(-7100 2500);
DISPLAY 0.638298 (-7100 2500);
PAINT RED (-7100 2500);
FORCEPROP 1 LAST PATH I224
J 0
(-6975 2700);
DISPLAY 0.978723 (-6975 2700);
PAINT WHITE (-6975 2700);
DISPLAY INVISIBLE (-6975 2700);
FORCEPROP 2 LAST CDS_LIB mstr_discrete
J 0
(-6925 2550);
DISPLAY 1.340426 (-6925 2550);
PAINT ORANGE (-6925 2550);
DISPLAY INVISIBLE (-6925 2550);
FORCEPROP 2 LAST BOM_COST PROC_SIDEBAND
J 0
(-6925 2550);
PAINT MONO (-6925 2550);
DISPLAY INVISIBLE (-6925 2550);
FORCEPROP 1 LAST MATERIAL CHIP
J 0
(-6775 2450);
DISPLAY 0.510638 (-6775 2450);
PAINT SKYBLUE (-6775 2450);
DISPLAY INVISIBLE (-6775 2450);
FORCEPROP 2 LAST ROOM CPU0
J 0
(-6975 2700);
PAINT PEACH (-6975 2700);
DISPLAY INVISIBLE (-6975 2700);
FORCEPROP 2 LAST SEC_TYPE 0402
J 0
(-6975 2775);
DISPLAY 1.021277 (-6975 2775);
PAINT ORANGE (-6975 2775);
DISPLAY INVISIBLE (-6975 2775);
FORCEPROP 2 LAST SEC 1
J 0
(-6975 2775);
DISPLAY 0.680851 (-6975 2775);
PAINT MONO (-6975 2775);
DISPLAY INVISIBLE (-6975 2775);
FORCEPROP 2 LAST CDS_LOCATION R2W4
J 0
(-7400 2550);
DISPLAY 0.617021 (-7400 2550);
PAINT AQUA (-7400 2550);
DISPLAY INVISIBLE (-7400 2550);
FORCEADD RES..1
(-6950 4400);
FORCEPROP 1 LAST PART_NUMBER G21497-005
J 0
(-7050 4450);
DISPLAY 0.617021 (-7050 4450);
PAINT BLUE (-7050 4450);
FORCEPROP 1 LAST PACK_TYPE 0402
J 0
(-6950 4550);
DISPLAY 0.617021 (-6950 4550);
PAINT SKYBLUE (-6950 4550);
FORCEPROP 1 LAST VALUE 0.0
J 0
(-6900 4600);
DISPLAY 0.617021 (-6900 4600);
PAINT SKYBLUE (-6900 4600);
FORCEPROP 1 LAST WATTAGE 1/16W
J 0
(-7050 4500);
DISPLAY 0.638298 (-7050 4500);
PAINT SKYBLUE (-7050 4500);
FORCEPROP 1 LASTPIN (-7050 4400) $PN 1
J 0
(-7038 4412);
DISPLAY 0.617021 (-7038 4412);
PAINT WHITE (-7038 4412);
FORCEPROP 1 LASTPIN (-6850 4400) $PN 2
J 0
(-6888 4412);
DISPLAY 0.617021 (-6888 4412);
PAINT WHITE (-6888 4412);
FORCEPROP 1 LAST TOLERANCE 5%
J 0
(-7050 4550);
DISPLAY 0.617021 (-7050 4550);
PAINT SKYBLUE (-7050 4550);
FORCEPROP 1 LAST LOCATION R7W13
J 0
(-7050 4600);
DISPLAY 0.617021 (-7050 4600);
PAINT AQUA (-7050 4600);
FORCEPROP 2 LAST CDS_LOCATION R7W13
J 0
(-7425 4400);
DISPLAY 0.617021 (-7425 4400);
PAINT AQUA (-7425 4400);
DISPLAY INVISIBLE (-7425 4400);
FORCEPROP 1 LAST PATH I226
J 0
(-7000 4550);
DISPLAY 0.978723 (-7000 4550);
PAINT WHITE (-7000 4550);
DISPLAY INVISIBLE (-7000 4550);
FORCEPROP 2 LAST CDS_LIB mstr_discrete
J 0
(-6950 4400);
DISPLAY 1.340426 (-6950 4400);
PAINT ORANGE (-6950 4400);
DISPLAY INVISIBLE (-6950 4400);
FORCEPROP 2 LAST BOM_COST PROC_SIDEBAND
J 0
(-6950 4400);
PAINT MONO (-6950 4400);
DISPLAY INVISIBLE (-6950 4400);
FORCEPROP 1 LAST MATERIAL CHIP
J 0
(-6800 4300);
DISPLAY 0.510638 (-6800 4300);
PAINT SKYBLUE (-6800 4300);
DISPLAY INVISIBLE (-6800 4300);
FORCEPROP 2 LAST ROOM CPU0
J 0
(-7000 4550);
PAINT PEACH (-7000 4550);
DISPLAY INVISIBLE (-7000 4550);
FORCEPROP 2 LAST SEC_TYPE 0402
J 0
(-7000 4625);
DISPLAY 1.021277 (-7000 4625);
PAINT ORANGE (-7000 4625);
DISPLAY INVISIBLE (-7000 4625);
FORCEPROP 2 LAST SEC 1
J 0
(-7000 4625);
DISPLAY 0.680851 (-7000 4625);
PAINT MONO (-7000 4625);
DISPLAY INVISIBLE (-7000 4625);
FORCEADD RES..1
(-6700 4300);
FORCEPROP 1 LASTPIN (-6800 4300) $PN 1
J 0
(-6788 4312);
DISPLAY 0.617021 (-6788 4312);
PAINT WHITE (-6788 4312);
FORCEPROP 1 LAST PART_NUMBER G21497-005
J 0
(-6800 4350);
DISPLAY 0.617021 (-6800 4350);
PAINT BLUE (-6800 4350);
FORCEPROP 0 LAST POP NOPOP
J 0
(-6750 4300);
DISPLAY 0.638298 (-6750 4300);
PAINT RED (-6750 4300);
FORCEPROP 1 LAST VALUE 0.0
J 0
(-6625 4500);
DISPLAY 0.617021 (-6625 4500);
PAINT SKYBLUE (-6625 4500);
FORCEPROP 1 LAST PACK_TYPE 0402
J 0
(-6700 4450);
DISPLAY 0.617021 (-6700 4450);
PAINT SKYBLUE (-6700 4450);
FORCEPROP 1 LAST TOLERANCE 5%
J 0
(-6800 4450);
DISPLAY 0.617021 (-6800 4450);
PAINT SKYBLUE (-6800 4450);
FORCEPROP 1 LAST LOCATION R7W15
J 0
(-6800 4500);
DISPLAY 0.617021 (-6800 4500);
PAINT AQUA (-6800 4500);
FORCEPROP 1 LAST WATTAGE 1/16W
J 0
(-6800 4400);
DISPLAY 0.638298 (-6800 4400);
PAINT SKYBLUE (-6800 4400);
FORCEPROP 1 LASTPIN (-6600 4300) $PN 2
J 0
(-6613 4312);
DISPLAY 0.617021 (-6613 4312);
PAINT WHITE (-6613 4312);
FORCEPROP 2 LAST CDS_LOCATION R7W15
J 0
(-7175 4300);
DISPLAY 0.617021 (-7175 4300);
PAINT AQUA (-7175 4300);
DISPLAY INVISIBLE (-7175 4300);
FORCEPROP 1 LAST PATH I227
J 0
(-6750 4450);
DISPLAY 0.978723 (-6750 4450);
PAINT WHITE (-6750 4450);
DISPLAY INVISIBLE (-6750 4450);
FORCEPROP 2 LAST SEC 1
J 0
(-6750 4525);
DISPLAY 0.680851 (-6750 4525);
PAINT MONO (-6750 4525);
DISPLAY INVISIBLE (-6750 4525);
FORCEPROP 2 LAST SEC_TYPE 0402
J 0
(-6750 4525);
DISPLAY 1.021277 (-6750 4525);
PAINT ORANGE (-6750 4525);
DISPLAY INVISIBLE (-6750 4525);
FORCEPROP 2 LAST ROOM CPU0
J 0
(-6750 4450);
PAINT PEACH (-6750 4450);
DISPLAY INVISIBLE (-6750 4450);
FORCEPROP 1 LAST MATERIAL CHIP
J 0
(-6550 4200);
DISPLAY 0.510638 (-6550 4200);
PAINT SKYBLUE (-6550 4200);
DISPLAY INVISIBLE (-6550 4200);
FORCEPROP 2 LAST BOM_COST PROC_SIDEBAND
J 0
(-6700 4300);
PAINT MONO (-6700 4300);
DISPLAY INVISIBLE (-6700 4300);
FORCEPROP 2 LAST CDS_LIB mstr_discrete
J 0
(-6700 4300);
DISPLAY 1.340426 (-6700 4300);
PAINT ORANGE (-6700 4300);
DISPLAY INVISIBLE (-6700 4300);
FORCEPROP 0 LAST CDS_SEC 1
J 0
(-6650 4450);
DISPLAY INVISIBLE (-6650 4450);
FORCEADD RES..1
(-1475 4100);
FORCEPROP 1 LAST PACK_TYPE 0402
J 0
(-1575 3950);
DISPLAY 0.617021 (-1575 3950);
PAINT SKYBLUE (-1575 3950);
FORCEPROP 1 LASTPIN (-1375 4100) $PN 2
J 0
(-1413 4112);
DISPLAY 0.617021 (-1413 4112);
PAINT WHITE (-1413 4112);
FORCEPROP 1 LASTPIN (-1575 4100) $PN 1
J 0
(-1563 4112);
DISPLAY 0.617021 (-1563 4112);
PAINT WHITE (-1563 4112);
FORCEPROP 0 LAST POP NOPOP
J 0
(-1575 3850);
DISPLAY 0.638298 (-1575 3850);
PAINT RED (-1575 3850);
FORCEPROP 1 LAST VALUE 0.0
J 0
(-1575 4000);
DISPLAY 0.617021 (-1575 4000);
PAINT SKYBLUE (-1575 4000);
FORCEPROP 1 LAST WATTAGE 1/16W
J 0
(-1475 3950);
DISPLAY 0.638298 (-1475 3950);
PAINT SKYBLUE (-1475 3950);
FORCEPROP 1 LAST TOLERANCE 5%
J 0
(-1500 4000);
DISPLAY 0.617021 (-1500 4000);
PAINT SKYBLUE (-1500 4000);
FORCEPROP 1 LAST LOCATION R2U50
J 0
(-1575 4050);
DISPLAY 0.617021 (-1575 4050);
PAINT AQUA (-1575 4050);
FORCEPROP 1 LAST PART_NUMBER G21497-005
J 0
(-1575 3900);
DISPLAY 0.617021 (-1575 3900);
PAINT BLUE (-1575 3900);
FORCEPROP 2 LAST CDS_LOCATION R2U50
J 0
(-1950 4100);
DISPLAY 0.617021 (-1950 4100);
PAINT AQUA (-1950 4100);
DISPLAY INVISIBLE (-1950 4100);
FORCEPROP 2 LAST SEC 1
J 0
(-1525 4325);
DISPLAY 0.680851 (-1525 4325);
PAINT MONO (-1525 4325);
DISPLAY INVISIBLE (-1525 4325);
FORCEPROP 2 LAST SEC_TYPE 0402
J 0
(-1525 4325);
DISPLAY 1.021277 (-1525 4325);
PAINT ORANGE (-1525 4325);
DISPLAY INVISIBLE (-1525 4325);
FORCEPROP 2 LAST ROOM CPU0
J 0
(-1525 4250);
PAINT PEACH (-1525 4250);
DISPLAY INVISIBLE (-1525 4250);
FORCEPROP 1 LAST MATERIAL CHIP
J 0
(-1325 4000);
DISPLAY 0.510638 (-1325 4000);
PAINT SKYBLUE (-1325 4000);
DISPLAY INVISIBLE (-1325 4000);
FORCEPROP 2 LAST BOM_COST PROC_SIDEBAND
J 0
(-1475 4100);
PAINT MONO (-1475 4100);
DISPLAY INVISIBLE (-1475 4100);
FORCEPROP 2 LAST CDS_LIB mstr_discrete
J 0
(-1475 4100);
DISPLAY 1.340426 (-1475 4100);
PAINT ORANGE (-1475 4100);
DISPLAY INVISIBLE (-1475 4100);
FORCEPROP 1 LAST PATH I228
J 0
(-1525 4250);
DISPLAY 0.978723 (-1525 4250);
PAINT WHITE (-1525 4250);
DISPLAY INVISIBLE (-1525 4250);
FORCEADD RES..1
(-1550 4250);
FORCEPROP 1 LAST WATTAGE 1/16W
J 0
(-1275 4300);
DISPLAY 0.638298 (-1275 4300);
PAINT SKYBLUE (-1275 4300);
FORCEPROP 1 LAST PACK_TYPE 0402
J 0
(-1375 4300);
DISPLAY 0.617021 (-1375 4300);
PAINT SKYBLUE (-1375 4300);
FORCEPROP 1 LAST TOLERANCE 5%
J 0
(-1450 4300);
DISPLAY 0.617021 (-1450 4300);
PAINT SKYBLUE (-1450 4300);
FORCEPROP 1 LAST VALUE 0.0
J 0
(-1525 4300);
DISPLAY 0.617021 (-1525 4300);
PAINT SKYBLUE (-1525 4300);
FORCEPROP 1 LAST LOCATION R7W17
J 0
(-1650 4300);
DISPLAY 0.617021 (-1650 4300);
PAINT AQUA (-1650 4300);
FORCEPROP 1 LASTPIN (-1450 4250) $PN 2
J 0
(-1488 4262);
DISPLAY 0.617021 (-1488 4262);
PAINT WHITE (-1488 4262);
FORCEPROP 1 LASTPIN (-1650 4250) $PN 1
J 0
(-1638 4262);
DISPLAY 0.617021 (-1638 4262);
PAINT WHITE (-1638 4262);
FORCEPROP 1 LAST PART_NUMBER G21497-005
J 0
(-1125 4300);
DISPLAY 0.617021 (-1125 4300);
PAINT BLUE (-1125 4300);
FORCEPROP 2 LAST CDS_LOCATION R7W17
J 0
(-2025 4250);
DISPLAY 0.617021 (-2025 4250);
PAINT AQUA (-2025 4250);
DISPLAY INVISIBLE (-2025 4250);
FORCEPROP 2 LAST CDS_LIB mstr_discrete
J 0
(-1550 4250);
DISPLAY 1.340426 (-1550 4250);
PAINT ORANGE (-1550 4250);
DISPLAY INVISIBLE (-1550 4250);
FORCEPROP 2 LAST BOM_COST PROC_SIDEBAND
J 0
(-1550 4250);
PAINT MONO (-1550 4250);
DISPLAY INVISIBLE (-1550 4250);
FORCEPROP 1 LAST MATERIAL CHIP
J 0
(-1400 4150);
DISPLAY 0.510638 (-1400 4150);
PAINT SKYBLUE (-1400 4150);
DISPLAY INVISIBLE (-1400 4150);
FORCEPROP 2 LAST ROOM CPU0
J 0
(-1600 4400);
PAINT PEACH (-1600 4400);
DISPLAY INVISIBLE (-1600 4400);
FORCEPROP 2 LAST SEC_TYPE 0402
J 0
(-1600 4475);
DISPLAY 1.021277 (-1600 4475);
PAINT ORANGE (-1600 4475);
DISPLAY INVISIBLE (-1600 4475);
FORCEPROP 2 LAST SEC 1
J 0
(-1600 4475);
DISPLAY 0.680851 (-1600 4475);
PAINT MONO (-1600 4475);
DISPLAY INVISIBLE (-1600 4475);
FORCEPROP 1 LAST PATH I229
J 0
(-1600 4400);
DISPLAY 0.978723 (-1600 4400);
PAINT WHITE (-1600 4400);
DISPLAY INVISIBLE (-1600 4400);
FORCEADD OFFPAGE..5
(-7175 3150);
FORCEPROP 2 LAST $XR1 134 
J 0
(-7580 3150);
DISPLAY 0.638298 (-7580 3150);
PAINT MONO (-7580 3150);
FORCEPROP 2 LAST $XR0 126 
J 0
(-7460 3150);
DISPLAY 0.638298 (-7460 3150);
PAINT MONO (-7460 3150);
FORCEPROP 1 LAST COMMENT_BODY TRUE
J 0
(-7075 3075);
DISPLAY 1.404255 (-7075 3075);
PAINT PEACH (-7075 3075);
DISPLAY INVISIBLE (-7075 3075);
FORCEPROP 1 LAST OFFPAGE TRUE
J 0
(-6850 3025);
PAINT GREEN (-6850 3025);
DISPLAY INVISIBLE (-6850 3025);
FORCEPROP 2 LAST CDS_LIB mstr_standard
J 0
(-7175 3150);
PAINT ORANGE (-7175 3150);
DISPLAY INVISIBLE (-7175 3150);
FORCEPROP 2 LAST PATH I23
J 0
(-7425 3200);
DISPLAY 1.021277 (-7425 3200);
PAINT ORANGE (-7425 3200);
DISPLAY INVISIBLE (-7425 3200);
FORCEADD RES..2
(-1700 1600);
FORCEPROP 1 LAST TOLERANCE 1%
J 0
(-1655 1625);
DISPLAY 0.617021 (-1655 1625);
PAINT SKYBLUE (-1655 1625);
FORCEPROP 1 LASTPIN (-1700 1500) $PN 2
J 0
(-1695 1510);
DISPLAY 0.617021 (-1695 1510);
PAINT ORANGE (-1695 1510);
FORCEPROP 1 LAST PACK_TYPE 0402
J 0
(-1660 1425);
DISPLAY 0.617021 (-1660 1425);
PAINT SKYBLUE (-1660 1425);
FORCEPROP 0 LAST POP NOPOP
J 0
(-1650 1375);
DISPLAY 0.638298 (-1650 1375);
PAINT RED (-1650 1375);
FORCEPROP 1 LAST PART_NUMBER G21796-072
J 0
(-1660 1475);
DISPLAY 0.617021 (-1660 1475);
PAINT BLUE (-1660 1475);
FORCEPROP 1 LAST MATERIAL CHIP
J 0
(-1660 1525);
DISPLAY 0.617021 (-1660 1525);
PAINT SKYBLUE (-1660 1525);
FORCEPROP 1 LAST WATTAGE 1/16W
J 0
(-1660 1575);
DISPLAY 0.617021 (-1660 1575);
PAINT SKYBLUE (-1660 1575);
FORCEPROP 1 LASTPIN (-1700 1700) $PN 1
J 0
(-1695 1662);
DISPLAY 0.617021 (-1695 1662);
PAINT ORANGE (-1695 1662);
FORCEPROP 1 LAST VALUE 4.75K
J 0
(-1655 1675);
DISPLAY 0.617021 (-1655 1675);
PAINT SKYBLUE (-1655 1675);
FORCEPROP 1 LAST LOCATION R7W22
J 0
(-1655 1725);
DISPLAY 0.617021 (-1655 1725);
PAINT AQUA (-1655 1725);
FORCEPROP 0 LAST CDS_SEC 1
J 0
(-1650 1775);
DISPLAY INVISIBLE (-1650 1775);
FORCEPROP 2 LAST CDS_LIB mstr_discrete
J 0
(-1700 1600);
PAINT ORANGE (-1700 1600);
DISPLAY INVISIBLE (-1700 1600);
FORCEPROP 2 LAST SEC_TYPE 0402
J 0
(-1650 1825);
DISPLAY 1.021277 (-1650 1825);
PAINT ORANGE (-1650 1825);
DISPLAY INVISIBLE (-1650 1825);
FORCEPROP 2 LAST SEC 1
J 0
(-1650 1825);
DISPLAY 0.680851 (-1650 1825);
PAINT MONO (-1650 1825);
DISPLAY INVISIBLE (-1650 1825);
FORCEPROP 0 LAST ROOM CPU0
J 0
(-1650 1825);
DISPLAY 1.021277 (-1650 1825);
PAINT ORANGE (-1650 1825);
DISPLAY INVISIBLE (-1650 1825);
FORCEPROP 1 LAST PATH I230
J 0
(-1650 1775);
DISPLAY 0.978723 (-1650 1775);
PAINT WHITE (-1650 1775);
DISPLAY INVISIBLE (-1650 1775);
FORCEPROP 2 LAST CDS_LOCATION R7W22
J 0
(-1655 1725);
DISPLAY 0.617021 (-1655 1725);
PAINT AQUA (-1655 1725);
DISPLAY INVISIBLE (-1655 1725);
FORCEADD P3V3_STBY..1
(-1700 1800);
FORCEPROP 3 LASTPIN (-1700 1750) SIG_NAME P3V3_STBY\g
J 0
(-1690 1760);
DISPLAY 0.659574 (-1690 1760);
PAINT MONO (-1690 1760);
DISPLAY INVISIBLE (-1690 1760);
FORCEPROP 1 LAST VOLTAGE 3.3V
J 0
(-1745 1757);
DISPLAY 0.340426 (-1745 1757);
PAINT SKYBLUE (-1745 1757);
DISPLAY INVISIBLE (-1745 1757);
FORCEPROP 2 LAST CDS_LIB mstr_symbols
J 0
(-1700 1800);
PAINT MONO (-1700 1800);
DISPLAY INVISIBLE (-1700 1800);
FORCEPROP 1 LAST SIZE 1B
J 0
(-1655 1822);
DISPLAY 0.340426 (-1655 1822);
PAINT GREEN (-1655 1822);
DISPLAY INVISIBLE (-1655 1822);
FORCEPROP 1 LAST BODY_TYPE PLUMBING
J 0
(-1745 1757);
DISPLAY 0.340426 (-1745 1757);
PAINT GREEN (-1745 1757);
DISPLAY INVISIBLE (-1745 1757);
FORCEPROP 1 LAST HDL_POWER P3V3_STBY
J 0
(-2000 1675);
DISPLAY 0.872340 (-2000 1675);
PAINT ORANGE (-2000 1675);
DISPLAY INVISIBLE (-2000 1675);
FORCEPROP 1 LAST PATH I231
J 0
(-1655 1802);
DISPLAY 0.340426 (-1655 1802);
PAINT GREEN (-1655 1802);
DISPLAY INVISIBLE (-1655 1802);
FORCEADD OFFPAGE..5
(-7175 2900);
FORCEPROP 2 LAST $XR2 191 
J 0
(-7700 2900);
DISPLAY 0.638298 (-7700 2900);
PAINT MONO (-7700 2900);
FORCEPROP 2 LAST $XR1 144 
J 0
(-7580 2900);
DISPLAY 0.638298 (-7580 2900);
PAINT MONO (-7580 2900);
FORCEPROP 2 LAST $XR0 125 
J 0
(-7460 2900);
DISPLAY 0.638298 (-7460 2900);
PAINT MONO (-7460 2900);
FORCEPROP 1 LAST COMMENT_BODY TRUE
J 0
(-7075 2825);
DISPLAY 0.872340 (-7075 2825);
PAINT GREEN (-7075 2825);
DISPLAY INVISIBLE (-7075 2825);
FORCEPROP 1 LAST OFFPAGE TRUE
J 0
(-6850 2775);
DISPLAY 0.872340 (-6850 2775);
PAINT GREEN (-6850 2775);
DISPLAY INVISIBLE (-6850 2775);
FORCEPROP 2 LAST PATH I26
J 0
(-7125 2975);
DISPLAY 1.021277 (-7125 2975);
PAINT ORANGE (-7125 2975);
DISPLAY INVISIBLE (-7125 2975);
FORCEPROP 2 LAST CDS_LIB mstr_standard
J 0
(-7175 2900);
PAINT ORANGE (-7175 2900);
DISPLAY INVISIBLE (-7175 2900);
FORCEADD OFFPAGE..5
(-7750 2650);
FORCEPROP 1 LAST COMMENT_BODY TRUE
J 0
(-7650 2575);
DISPLAY 1.404255 (-7650 2575);
PAINT PEACH (-7650 2575);
DISPLAY INVISIBLE (-7650 2575);
FORCEPROP 1 LAST OFFPAGE TRUE
J 0
(-7425 2525);
PAINT GREEN (-7425 2525);
DISPLAY INVISIBLE (-7425 2525);
FORCEPROP 2 LAST CDS_LIB mstr_standard
J 0
(-7750 2650);
PAINT ORANGE (-7750 2650);
DISPLAY INVISIBLE (-7750 2650);
FORCEPROP 2 LAST PATH I29
J 0
(-8000 2700);
DISPLAY 1.021277 (-8000 2700);
PAINT ORANGE (-8000 2700);
DISPLAY INVISIBLE (-8000 2700);
FORCEPROP 2 LAST $XR3 247 
J 0
(-8179 2650);
DISPLAY 0.638298 (-8179 2650);
PAINT MONO (-8179 2650);
DISPLAY INVISIBLE (-8179 2650);
FORCEPROP 2 LAST $XR2 191 
J 0
(-8179 2650);
DISPLAY 0.638298 (-8179 2650);
PAINT MONO (-8179 2650);
DISPLAY INVISIBLE (-8179 2650);
FORCEPROP 2 LAST $XR1 139 
J 0
(-8179 2650);
DISPLAY 0.638298 (-8179 2650);
PAINT MONO (-8179 2650);
DISPLAY INVISIBLE (-8179 2650);
FORCEPROP 2 LAST $XR0 136 
J 0
(-8179 2650);
DISPLAY 0.638298 (-8179 2650);
PAINT MONO (-8179 2650);
DISPLAY INVISIBLE (-8179 2650);
FORCEADD OFFPAGE..1
(-7175 2100);
FORCEPROP 2 LAST $XR0 133 
J 0
(-7427 2100);
DISPLAY 0.638298 (-7427 2100);
PAINT MONO (-7427 2100);
FORCEPROP 1 LAST COMMENT_BODY TRUE
J 0
(-7050 2000);
DISPLAY 1.404255 (-7050 2000);
PAINT PEACH (-7050 2000);
DISPLAY INVISIBLE (-7050 2000);
FORCEPROP 1 LAST OFFPAGE TRUE
J 0
(-6850 1975);
PAINT GREEN (-6850 1975);
DISPLAY INVISIBLE (-6850 1975);
FORCEPROP 2 LAST PATH I31
J 0
(-7125 2175);
DISPLAY 1.021277 (-7125 2175);
PAINT ORANGE (-7125 2175);
DISPLAY INVISIBLE (-7125 2175);
FORCEPROP 2 LAST CDS_LIB mstr_standard
J 0
(-7175 2100);
PAINT ORANGE (-7175 2100);
DISPLAY INVISIBLE (-7175 2100);
FORCEADD OFFPAGE..2
(-775 3500);
FORCEPROP 2 LAST $XR1 146 
J 0
(-466 3500);
DISPLAY 0.638298 (-466 3500);
PAINT MONO (-466 3500);
FORCEPROP 2 LAST $XR0 126 
J 0
(-586 3500);
DISPLAY 0.638298 (-586 3500);
PAINT MONO (-586 3500);
FORCEPROP 1 LAST COMMENT_BODY TRUE
J 0
(-820 3405);
DISPLAY 1.404255 (-820 3405);
PAINT PEACH (-820 3405);
DISPLAY INVISIBLE (-820 3405);
FORCEPROP 1 LAST OFFPAGE TRUE
J 0
(-450 3375);
PAINT GREEN (-450 3375);
DISPLAY INVISIBLE (-450 3375);
FORCEPROP 2 LAST PATH I32
J 0
(-575 3550);
DISPLAY 1.021277 (-575 3550);
PAINT ORANGE (-575 3550);
DISPLAY INVISIBLE (-575 3550);
FORCEPROP 2 LAST CDS_LIB mstr_standard
J 0
(-775 3500);
PAINT ORANGE (-775 3500);
DISPLAY INVISIBLE (-775 3500);
FORCEADD OFFPAGE..3
(-775 3450);
FORCEPROP 2 LAST $XR0 138 
J 0
(-561 3450);
DISPLAY 0.638298 (-561 3450);
PAINT MONO (-561 3450);
FORCEPROP 1 LAST COMMENT_BODY TRUE
J 0
(-825 3350);
DISPLAY 1.404255 (-825 3350);
PAINT PEACH (-825 3350);
DISPLAY INVISIBLE (-825 3350);
FORCEPROP 1 LAST OFFPAGE TRUE
J 0
(-450 3325);
PAINT GREEN (-450 3325);
DISPLAY INVISIBLE (-450 3325);
FORCEPROP 2 LAST PATH I33
J 0
(-550 3500);
DISPLAY 1.021277 (-550 3500);
PAINT ORANGE (-550 3500);
DISPLAY INVISIBLE (-550 3500);
FORCEPROP 2 LAST CDS_LIB mstr_standard
J 0
(-775 3450);
PAINT ORANGE (-775 3450);
DISPLAY INVISIBLE (-775 3450);
FORCEADD OFFPAGE..2
(-775 3550);
FORCEPROP 2 LAST $XR0 247 
J 0
(-586 3550);
DISPLAY 0.638298 (-586 3550);
PAINT MONO (-586 3550);
FORCEPROP 1 LAST COMMENT_BODY TRUE
J 0
(-820 3455);
DISPLAY 0.872340 (-820 3455);
PAINT GREEN (-820 3455);
DISPLAY INVISIBLE (-820 3455);
FORCEPROP 1 LAST OFFPAGE TRUE
J 0
(-450 3425);
DISPLAY 0.872340 (-450 3425);
PAINT GREEN (-450 3425);
DISPLAY INVISIBLE (-450 3425);
FORCEPROP 2 LAST PATH I34
J 0
(-550 3600);
DISPLAY 1.021277 (-550 3600);
PAINT ORANGE (-550 3600);
DISPLAY INVISIBLE (-550 3600);
FORCEPROP 2 LAST CDS_LIB mstr_standard
J 0
(-775 3550);
PAINT ORANGE (-775 3550);
DISPLAY INVISIBLE (-775 3550);
FORCEADD OFFPAGE..4
(-775 3650);
FORCEPROP 2 LAST $XR0 136 
J 0
(-589 3650);
DISPLAY 0.638298 (-589 3650);
PAINT MONO (-589 3650);
FORCEPROP 1 LAST COMMENT_BODY TRUE
J 0
(-800 3550);
DISPLAY 1.404255 (-800 3550);
PAINT PEACH (-800 3550);
DISPLAY INVISIBLE (-800 3550);
FORCEPROP 1 LAST OFFPAGE TRUE
J 0
(-450 3525);
PAINT GREEN (-450 3525);
DISPLAY INVISIBLE (-450 3525);
FORCEPROP 2 LAST PATH I35
J 0
(-575 3700);
DISPLAY 1.021277 (-575 3700);
PAINT ORANGE (-575 3700);
DISPLAY INVISIBLE (-575 3700);
FORCEPROP 2 LAST CDS_LIB mstr_standard
J 0
(-775 3650);
PAINT ORANGE (-775 3650);
DISPLAY INVISIBLE (-775 3650);
FORCEADD OFFPAGE..3
(-775 3750);
FORCEPROP 2 LAST $XR0 135 
J 0
(-561 3750);
DISPLAY 0.638298 (-561 3750);
PAINT MONO (-561 3750);
FORCEPROP 1 LAST COMMENT_BODY TRUE
J 0
(-825 3650);
DISPLAY 1.404255 (-825 3650);
PAINT PEACH (-825 3650);
DISPLAY INVISIBLE (-825 3650);
FORCEPROP 1 LAST OFFPAGE TRUE
J 0
(-450 3625);
PAINT GREEN (-450 3625);
DISPLAY INVISIBLE (-450 3625);
FORCEPROP 2 LAST PATH I37
J 0
(-550 3800);
DISPLAY 1.021277 (-550 3800);
PAINT ORANGE (-550 3800);
DISPLAY INVISIBLE (-550 3800);
FORCEPROP 2 LAST CDS_LIB mstr_standard
J 0
(-775 3750);
PAINT ORANGE (-775 3750);
DISPLAY INVISIBLE (-775 3750);
FORCEADD OFFPAGE..4
(-775 4400);
FORCEPROP 2 LAST $XR0 190 
J 0
(-589 4400);
DISPLAY 0.638298 (-589 4400);
PAINT MONO (-589 4400);
FORCEPROP 1 LAST COMMENT_BODY TRUE
J 0
(-800 4300);
DISPLAY 1.404255 (-800 4300);
PAINT PEACH (-800 4300);
DISPLAY INVISIBLE (-800 4300);
FORCEPROP 1 LAST OFFPAGE TRUE
J 0
(-450 4275);
PAINT GREEN (-450 4275);
DISPLAY INVISIBLE (-450 4275);
FORCEPROP 2 LAST PATH I39
J 0
(-600 4475);
DISPLAY 1.021277 (-600 4475);
PAINT ORANGE (-600 4475);
DISPLAY INVISIBLE (-600 4475);
FORCEPROP 2 LAST CDS_LIB mstr_standard
J 0
(-775 4400);
PAINT ORANGE (-775 4400);
DISPLAY INVISIBLE (-775 4400);
FORCEADD OFFPAGE..4
(-775 4350);
FORCEPROP 2 LAST $XR2 144 
J 0
(-259 4350);
DISPLAY 0.638298 (-259 4350);
PAINT MONO (-259 4350);
FORCEPROP 2 LAST $XR1 133 
J 0
(-379 4350);
DISPLAY 0.638298 (-379 4350);
PAINT MONO (-379 4350);
FORCEPROP 2 LAST $XR0 120 
J 0
(-499 4350);
DISPLAY 0.638298 (-499 4350);
PAINT MONO (-499 4350);
FORCEPROP 1 LAST COMMENT_BODY TRUE
J 0
(-800 4250);
DISPLAY 1.404255 (-800 4250);
PAINT PEACH (-800 4250);
DISPLAY INVISIBLE (-800 4250);
FORCEPROP 1 LAST OFFPAGE TRUE
J 0
(-450 4225);
PAINT GREEN (-450 4225);
DISPLAY INVISIBLE (-450 4225);
FORCEPROP 2 LAST PATH I40
J 0
(-600 4425);
DISPLAY 1.021277 (-600 4425);
PAINT ORANGE (-600 4425);
DISPLAY INVISIBLE (-600 4425);
FORCEPROP 2 LAST CDS_LIB mstr_standard
J 0
(-775 4350);
PAINT ORANGE (-775 4350);
DISPLAY INVISIBLE (-775 4350);
FORCEADD OFFPAGE..2
(-775 4250);
FORCEPROP 2 LAST $XR3 146 
J 0
(-256 4250);
DISPLAY 0.638298 (-256 4250);
PAINT MONO (-256 4250);
FORCEPROP 2 LAST $XR2 95 
J 0
(-346 4250);
DISPLAY 0.638298 (-346 4250);
PAINT MONO (-346 4250);
FORCEPROP 2 LAST $XR1 170 
J 0
(-466 4250);
DISPLAY 0.638298 (-466 4250);
PAINT MONO (-466 4250);
FORCEPROP 2 LAST $XR0 133 
J 0
(-586 4250);
DISPLAY 0.638298 (-586 4250);
PAINT MONO (-586 4250);
FORCEPROP 1 LAST COMMENT_BODY TRUE
J 0
(-820 4155);
DISPLAY 1.404255 (-820 4155);
PAINT PEACH (-820 4155);
DISPLAY INVISIBLE (-820 4155);
FORCEPROP 1 LAST OFFPAGE TRUE
J 0
(-450 4125);
PAINT GREEN (-450 4125);
DISPLAY INVISIBLE (-450 4125);
FORCEPROP 2 LAST PATH I42
J 0
(-450 4300);
DISPLAY 1.021277 (-450 4300);
PAINT ORANGE (-450 4300);
DISPLAY INVISIBLE (-450 4300);
FORCEPROP 2 LAST CDS_LIB mstr_standard
J 0
(-775 4250);
PAINT ORANGE (-775 4250);
DISPLAY INVISIBLE (-775 4250);
FORCEADD OFFPAGE..4
(-775 4050);
FORCEPROP 1 LAST COMMENT_BODY TRUE
J 0
(-800 3950);
DISPLAY 1.404255 (-800 3950);
PAINT PEACH (-800 3950);
DISPLAY INVISIBLE (-800 3950);
FORCEPROP 1 LAST OFFPAGE TRUE
J 0
(-450 3925);
PAINT GREEN (-450 3925);
DISPLAY INVISIBLE (-450 3925);
FORCEPROP 2 LAST PATH I46
J 0
(-600 4125);
DISPLAY 1.021277 (-600 4125);
PAINT ORANGE (-600 4125);
DISPLAY INVISIBLE (-600 4125);
FORCEPROP 2 LAST CDS_LIB mstr_standard
J 0
(-775 4050);
PAINT ORANGE (-775 4050);
DISPLAY INVISIBLE (-775 4050);
FORCEPROP 2 LAST $XR2 147 
J 0
(-589 4050);
DISPLAY 0.638298 (-589 4050);
PAINT MONO (-589 4050);
DISPLAY INVISIBLE (-589 4050);
FORCEPROP 2 LAST $XR1 133 
J 0
(-589 4050);
DISPLAY 0.638298 (-589 4050);
PAINT MONO (-589 4050);
DISPLAY INVISIBLE (-589 4050);
FORCEPROP 2 LAST $XR0 108 
J 0
(-589 4050);
DISPLAY 0.638298 (-589 4050);
PAINT MONO (-589 4050);
DISPLAY INVISIBLE (-589 4050);
FORCEADD OFFPAGE..4
(-775 3950);
FORCEPROP 2 LAST $XR2 146 
J 0
(-349 3950);
DISPLAY 0.638298 (-349 3950);
PAINT MONO (-349 3950);
FORCEPROP 2 LAST $XR1 133 
J 0
(-469 3950);
DISPLAY 0.638298 (-469 3950);
PAINT MONO (-469 3950);
FORCEPROP 2 LAST $XR0 120 
J 0
(-589 3950);
DISPLAY 0.638298 (-589 3950);
PAINT MONO (-589 3950);
FORCEPROP 1 LAST COMMENT_BODY TRUE
J 0
(-800 3850);
DISPLAY 1.404255 (-800 3850);
PAINT PEACH (-800 3850);
DISPLAY INVISIBLE (-800 3850);
FORCEPROP 1 LAST OFFPAGE TRUE
J 0
(-450 3825);
PAINT GREEN (-450 3825);
DISPLAY INVISIBLE (-450 3825);
FORCEPROP 2 LAST PATH I47
J 0
(-575 4000);
DISPLAY 1.021277 (-575 4000);
PAINT ORANGE (-575 4000);
DISPLAY INVISIBLE (-575 4000);
FORCEPROP 2 LAST CDS_LIB mstr_standard
J 0
(-775 3950);
PAINT ORANGE (-775 3950);
DISPLAY INVISIBLE (-775 3950);
FORCEADD OFFPAGE..4
(-775 4000);
FORCEPROP 2 LAST $XR2 147 
J 0
(-349 4000);
DISPLAY 0.638298 (-349 4000);
PAINT MONO (-349 4000);
FORCEPROP 2 LAST $XR1 133 
J 0
(-469 4000);
DISPLAY 0.638298 (-469 4000);
PAINT MONO (-469 4000);
FORCEPROP 2 LAST $XR0 108 
J 0
(-589 4000);
DISPLAY 0.638298 (-589 4000);
PAINT MONO (-589 4000);
FORCEPROP 1 LAST COMMENT_BODY TRUE
J 0
(-800 3900);
DISPLAY 1.404255 (-800 3900);
PAINT PEACH (-800 3900);
DISPLAY INVISIBLE (-800 3900);
FORCEPROP 1 LAST OFFPAGE TRUE
J 0
(-450 3875);
PAINT GREEN (-450 3875);
DISPLAY INVISIBLE (-450 3875);
FORCEPROP 2 LAST PATH I48
J 0
(-600 4075);
DISPLAY 1.021277 (-600 4075);
PAINT ORANGE (-600 4075);
DISPLAY INVISIBLE (-600 4075);
FORCEPROP 2 LAST CDS_LIB mstr_standard
J 0
(-775 4000);
PAINT ORANGE (-775 4000);
DISPLAY INVISIBLE (-775 4000);
FORCEADD OFFPAGE..4
(-775 3900);
FORCEPROP 2 LAST $XR1 145 
J 0
(-469 3900);
DISPLAY 0.638298 (-469 3900);
PAINT MONO (-469 3900);
FORCEPROP 2 LAST $XR0 164 
J 0
(-589 3900);
DISPLAY 0.638298 (-589 3900);
PAINT MONO (-589 3900);
FORCEPROP 1 LAST COMMENT_BODY TRUE
J 0
(-800 3800);
DISPLAY 1.404255 (-800 3800);
PAINT PEACH (-800 3800);
DISPLAY INVISIBLE (-800 3800);
FORCEPROP 1 LAST OFFPAGE TRUE
J 0
(-450 3775);
PAINT GREEN (-450 3775);
DISPLAY INVISIBLE (-450 3775);
FORCEPROP 2 LAST PATH I49
J 0
(-600 3975);
DISPLAY 1.021277 (-600 3975);
PAINT ORANGE (-600 3975);
DISPLAY INVISIBLE (-600 3975);
FORCEPROP 2 LAST CDS_LIB mstr_standard
J 0
(-775 3900);
PAINT ORANGE (-775 3900);
DISPLAY INVISIBLE (-775 3900);
FORCEADD OFFPAGE..4
(-775 3850);
FORCEPROP 2 LAST $XR1 145 
J 0
(-469 3850);
DISPLAY 0.638298 (-469 3850);
PAINT MONO (-469 3850);
FORCEPROP 2 LAST $XR0 164 
J 0
(-589 3850);
DISPLAY 0.638298 (-589 3850);
PAINT MONO (-589 3850);
FORCEPROP 1 LAST COMMENT_BODY TRUE
J 0
(-800 3750);
DISPLAY 1.404255 (-800 3750);
PAINT PEACH (-800 3750);
DISPLAY INVISIBLE (-800 3750);
FORCEPROP 1 LAST OFFPAGE TRUE
J 0
(-450 3725);
PAINT GREEN (-450 3725);
DISPLAY INVISIBLE (-450 3725);
FORCEPROP 2 LAST PATH I50
J 0
(-600 3925);
DISPLAY 1.021277 (-600 3925);
PAINT ORANGE (-600 3925);
DISPLAY INVISIBLE (-600 3925);
FORCEPROP 2 LAST CDS_LIB mstr_standard
J 0
(-775 3850);
PAINT ORANGE (-775 3850);
DISPLAY INVISIBLE (-775 3850);
FORCEADD OFFPAGE..3
(-775 3600);
FORCEPROP 2 LAST $XR0 247 
J 0
(-561 3600);
DISPLAY 0.638298 (-561 3600);
PAINT MONO (-561 3600);
FORCEPROP 1 LAST COMMENT_BODY TRUE
J 0
(-825 3500);
DISPLAY 1.404255 (-825 3500);
PAINT PEACH (-825 3500);
DISPLAY INVISIBLE (-825 3500);
FORCEPROP 1 LAST OFFPAGE TRUE
J 0
(-450 3475);
PAINT GREEN (-450 3475);
DISPLAY INVISIBLE (-450 3475);
FORCEPROP 2 LAST PATH I51
J 0
(-550 3650);
DISPLAY 1.021277 (-550 3650);
PAINT ORANGE (-550 3650);
DISPLAY INVISIBLE (-550 3650);
FORCEPROP 2 LAST CDS_LIB mstr_standard
J 0
(-775 3600);
PAINT ORANGE (-775 3600);
DISPLAY INVISIBLE (-775 3600);
FORCEADD OFFPAGE..2
(-775 3400);
FORCEPROP 2 LAST $XR0 138 
J 0
(-586 3400);
DISPLAY 0.638298 (-586 3400);
PAINT MONO (-586 3400);
FORCEPROP 1 LAST COMMENT_BODY TRUE
J 0
(-820 3305);
DISPLAY 0.872340 (-820 3305);
PAINT GREEN (-820 3305);
DISPLAY INVISIBLE (-820 3305);
FORCEPROP 1 LAST OFFPAGE TRUE
J 0
(-450 3275);
DISPLAY 0.872340 (-450 3275);
PAINT GREEN (-450 3275);
DISPLAY INVISIBLE (-450 3275);
FORCEPROP 2 LAST PATH I52
J 0
(-550 3450);
DISPLAY 1.021277 (-550 3450);
PAINT ORANGE (-550 3450);
DISPLAY INVISIBLE (-550 3450);
FORCEPROP 2 LAST CDS_LIB mstr_standard
J 0
(-775 3400);
PAINT ORANGE (-775 3400);
DISPLAY INVISIBLE (-775 3400);
FORCEADD OFFPAGE..4
(-775 3350);
FORCEPROP 2 LAST $XR1 125 
J 0
(-469 3350);
DISPLAY 0.638298 (-469 3350);
PAINT MONO (-469 3350);
FORCEPROP 2 LAST $XR0 108 
J 0
(-589 3350);
DISPLAY 0.638298 (-589 3350);
PAINT MONO (-589 3350);
FORCEPROP 1 LAST COMMENT_BODY TRUE
J 0
(-800 3250);
DISPLAY 0.872340 (-800 3250);
PAINT GREEN (-800 3250);
DISPLAY INVISIBLE (-800 3250);
FORCEPROP 1 LAST OFFPAGE TRUE
J 0
(-450 3225);
DISPLAY 0.872340 (-450 3225);
PAINT GREEN (-450 3225);
DISPLAY INVISIBLE (-450 3225);
FORCEPROP 2 LAST PATH I53
J 0
(-575 3425);
DISPLAY 1.021277 (-575 3425);
PAINT ORANGE (-575 3425);
DISPLAY INVISIBLE (-575 3425);
FORCEPROP 2 LAST CDS_LIB mstr_standard
J 0
(-775 3350);
PAINT ORANGE (-775 3350);
DISPLAY INVISIBLE (-775 3350);
FORCEADD OFFPAGE..3
(-775 3300);
FORCEPROP 2 LAST $XR0 138 
J 0
(-561 3300);
DISPLAY 0.638298 (-561 3300);
PAINT MONO (-561 3300);
FORCEPROP 1 LAST COMMENT_BODY TRUE
J 0
(-825 3200);
DISPLAY 0.872340 (-825 3200);
PAINT GREEN (-825 3200);
DISPLAY INVISIBLE (-825 3200);
FORCEPROP 1 LAST OFFPAGE TRUE
J 0
(-450 3175);
DISPLAY 0.872340 (-450 3175);
PAINT GREEN (-450 3175);
DISPLAY INVISIBLE (-450 3175);
FORCEPROP 2 LAST PATH I54
J 0
(-550 3350);
DISPLAY 1.021277 (-550 3350);
PAINT ORANGE (-550 3350);
DISPLAY INVISIBLE (-550 3350);
FORCEPROP 2 LAST CDS_LIB mstr_standard
J 0
(-775 3300);
PAINT ORANGE (-775 3300);
DISPLAY INVISIBLE (-775 3300);
FORCEADD OFFPAGE..2
(-775 3250);
FORCEPROP 2 LAST $XR0 138 
J 0
(-586 3250);
DISPLAY 0.638298 (-586 3250);
PAINT MONO (-586 3250);
FORCEPROP 1 LAST COMMENT_BODY TRUE
J 0
(-820 3155);
DISPLAY 0.872340 (-820 3155);
PAINT GREEN (-820 3155);
DISPLAY INVISIBLE (-820 3155);
FORCEPROP 1 LAST OFFPAGE TRUE
J 0
(-450 3125);
DISPLAY 0.872340 (-450 3125);
PAINT GREEN (-450 3125);
DISPLAY INVISIBLE (-450 3125);
FORCEPROP 2 LAST PATH I55
J 0
(-550 3300);
DISPLAY 1.021277 (-550 3300);
PAINT ORANGE (-550 3300);
DISPLAY INVISIBLE (-550 3300);
FORCEPROP 2 LAST CDS_LIB mstr_standard
J 0
(-775 3250);
PAINT ORANGE (-775 3250);
DISPLAY INVISIBLE (-775 3250);
FORCEADD OFFPAGE..2
(-775 2200);
FORCEPROP 2 LAST $XR1 190 
J 0
(-466 2200);
DISPLAY 0.638298 (-466 2200);
PAINT MONO (-466 2200);
FORCEPROP 2 LAST $XR0 133 
J 0
(-586 2200);
DISPLAY 0.638298 (-586 2200);
PAINT MONO (-586 2200);
FORCEPROP 1 LAST COMMENT_BODY TRUE
J 0
(-820 2105);
DISPLAY 0.872340 (-820 2105);
PAINT GREEN (-820 2105);
DISPLAY INVISIBLE (-820 2105);
FORCEPROP 1 LAST OFFPAGE TRUE
J 0
(-450 2075);
DISPLAY 0.872340 (-450 2075);
PAINT GREEN (-450 2075);
DISPLAY INVISIBLE (-450 2075);
FORCEPROP 2 LAST PATH I63
J 0
(-600 2275);
DISPLAY 1.021277 (-600 2275);
PAINT ORANGE (-600 2275);
DISPLAY INVISIBLE (-600 2275);
FORCEPROP 2 LAST CDS_LIB mstr_standard
J 0
(-775 2200);
PAINT ORANGE (-775 2200);
DISPLAY INVISIBLE (-775 2200);
FORCEADD OFFPAGE..4
(-775 2000);
FORCEPROP 2 LAST $XR0 156 
J 0
(-589 2000);
DISPLAY 0.638298 (-589 2000);
PAINT MONO (-589 2000);
FORCEPROP 1 LAST COMMENT_BODY TRUE
J 0
(-800 1900);
DISPLAY 1.404255 (-800 1900);
PAINT PEACH (-800 1900);
DISPLAY INVISIBLE (-800 1900);
FORCEPROP 1 LAST OFFPAGE TRUE
J 0
(-450 1875);
PAINT GREEN (-450 1875);
DISPLAY INVISIBLE (-450 1875);
FORCEPROP 2 LAST PATH I67
J 0
(-575 2050);
DISPLAY 1.021277 (-575 2050);
PAINT ORANGE (-575 2050);
DISPLAY INVISIBLE (-575 2050);
FORCEPROP 2 LAST CDS_LIB mstr_standard
J 0
(-775 2000);
PAINT ORANGE (-775 2000);
DISPLAY INVISIBLE (-775 2000);
FORCEADD OFFPAGE..2
R 2
(-6625 3500);
FORCEPROP 2 LAST $XR0 146 
J 0
(-6880 3500);
DISPLAY 0.638298 (-6880 3500);
PAINT MONO (-6880 3500);
FORCEPROP 2 LAST CDS_LIB mstr_standard
J 0
(-6625 3500);
PAINT ORANGE (-6625 3500);
DISPLAY INVISIBLE (-6625 3500);
FORCEPROP 2 LAST PATH I7
J 0
(-6575 3575);
DISPLAY 1.021277 (-6575 3575);
PAINT ORANGE (-6575 3575);
DISPLAY INVISIBLE (-6575 3575);
FORCEPROP 1 LAST OFFPAGE TRUE
J 2
(-6950 3375);
DISPLAY 0.872340 (-6950 3375);
PAINT GREEN (-6950 3375);
DISPLAY INVISIBLE (-6950 3375);
FORCEPROP 1 LAST COMMENT_BODY TRUE
J 2
(-6580 3405);
DISPLAY 0.872340 (-6580 3405);
PAINT PEACH (-6580 3405);
DISPLAY INVISIBLE (-6580 3405);
FORCEADD OFFPAGE..4
R 2
(-7550 3550);
FORCEPROP 2 LAST $XR1 146 
J 0
(-7922 3550);
DISPLAY 0.638298 (-7922 3550);
PAINT MONO (-7922 3550);
FORCEPROP 2 LAST $XR0 133 
J 0
(-7802 3550);
DISPLAY 0.638298 (-7802 3550);
PAINT MONO (-7802 3550);
FORCEPROP 2 LAST CDS_LIB mstr_standard
J 0
(-7550 3550);
PAINT ORANGE (-7550 3550);
DISPLAY INVISIBLE (-7550 3550);
FORCEPROP 2 LAST PATH I8
J 0
(-7500 3625);
DISPLAY 1.021277 (-7500 3625);
PAINT ORANGE (-7500 3625);
DISPLAY INVISIBLE (-7500 3625);
FORCEPROP 1 LAST OFFPAGE TRUE
J 2
(-7875 3425);
DISPLAY 0.872340 (-7875 3425);
PAINT GREEN (-7875 3425);
DISPLAY INVISIBLE (-7875 3425);
FORCEPROP 1 LAST COMMENT_BODY TRUE
J 2
(-7525 3450);
DISPLAY 0.872340 (-7525 3450);
PAINT GREEN (-7525 3450);
DISPLAY INVISIBLE (-7525 3450);
FORCEADD OFFPAGE..5
(-7175 2050);
FORCEPROP 2 LAST $XR0 235 
J 0
(-7460 2050);
DISPLAY 0.638298 (-7460 2050);
PAINT MONO (-7460 2050);
FORCEPROP 1 LAST COMMENT_BODY TRUE
J 0
(-7075 1975);
DISPLAY 1.404255 (-7075 1975);
PAINT PEACH (-7075 1975);
DISPLAY INVISIBLE (-7075 1975);
FORCEPROP 1 LAST OFFPAGE TRUE
J 0
(-6850 1925);
PAINT GREEN (-6850 1925);
DISPLAY INVISIBLE (-6850 1925);
FORCEPROP 2 LAST PATH I86
J 0
(-7125 2125);
DISPLAY 1.021277 (-7125 2125);
PAINT ORANGE (-7125 2125);
DISPLAY INVISIBLE (-7125 2125);
FORCEPROP 2 LAST CDS_LIB mstr_standard
J 0
(-7175 2050);
PAINT ORANGE (-7175 2050);
DISPLAY INVISIBLE (-7175 2050);
FORCEADD OFFPAGE..5
(-7175 2000);
FORCEPROP 2 LAST $XR0 235 
J 0
(-7460 2000);
DISPLAY 0.638298 (-7460 2000);
PAINT MONO (-7460 2000);
FORCEPROP 1 LAST COMMENT_BODY TRUE
J 0
(-7075 1925);
DISPLAY 1.404255 (-7075 1925);
PAINT PEACH (-7075 1925);
DISPLAY INVISIBLE (-7075 1925);
FORCEPROP 1 LAST OFFPAGE TRUE
J 0
(-6850 1875);
PAINT GREEN (-6850 1875);
DISPLAY INVISIBLE (-6850 1875);
FORCEPROP 2 LAST PATH I87
J 0
(-7125 2075);
DISPLAY 1.021277 (-7125 2075);
PAINT ORANGE (-7125 2075);
DISPLAY INVISIBLE (-7125 2075);
FORCEPROP 2 LAST CDS_LIB mstr_standard
J 0
(-7175 2000);
PAINT ORANGE (-7175 2000);
DISPLAY INVISIBLE (-7175 2000);
FORCEADD OFFPAGE..1
(-7175 2150);
FORCEPROP 2 LAST $XR0 135 
J 0
(-7427 2150);
DISPLAY 0.638298 (-7427 2150);
PAINT MONO (-7427 2150);
FORCEPROP 1 LAST COMMENT_BODY TRUE
J 0
(-7050 2050);
DISPLAY 1.404255 (-7050 2050);
PAINT PEACH (-7050 2050);
DISPLAY INVISIBLE (-7050 2050);
FORCEPROP 1 LAST OFFPAGE TRUE
J 0
(-6850 2025);
PAINT GREEN (-6850 2025);
DISPLAY INVISIBLE (-6850 2025);
FORCEPROP 2 LAST PATH I88
J 0
(-7125 2225);
DISPLAY 1.021277 (-7125 2225);
PAINT ORANGE (-7125 2225);
DISPLAY INVISIBLE (-7125 2225);
FORCEPROP 2 LAST CDS_LIB mstr_standard
J 0
(-7175 2150);
PAINT ORANGE (-7175 2150);
DISPLAY INVISIBLE (-7175 2150);
FORCEADD OFFPAGE..4
R 2
(-7550 3600);
FORCEPROP 2 LAST $XR1 184 
J 0
(-7922 3600);
DISPLAY 0.638298 (-7922 3600);
PAINT MONO (-7922 3600);
FORCEPROP 2 LAST $XR0 133 
J 0
(-7802 3600);
DISPLAY 0.638298 (-7802 3600);
PAINT MONO (-7802 3600);
FORCEPROP 2 LAST CDS_LIB mstr_standard
J 0
(-7550 3600);
PAINT ORANGE (-7550 3600);
DISPLAY INVISIBLE (-7550 3600);
FORCEPROP 2 LAST PATH I9
J 0
(-7500 3675);
DISPLAY 1.021277 (-7500 3675);
PAINT ORANGE (-7500 3675);
DISPLAY INVISIBLE (-7500 3675);
FORCEPROP 1 LAST OFFPAGE TRUE
J 2
(-7875 3475);
DISPLAY 0.872340 (-7875 3475);
PAINT GREEN (-7875 3475);
DISPLAY INVISIBLE (-7875 3475);
FORCEPROP 1 LAST COMMENT_BODY TRUE
J 2
(-7525 3500);
DISPLAY 0.872340 (-7525 3500);
PAINT GREEN (-7525 3500);
DISPLAY INVISIBLE (-7525 3500);
FORCEADD CAD_NOTE..1
(-3725 575);
FORCEPROP 0 LAST L1 PLEASE PLACE LED NEAR POWER BUTTON S9A2
J 0
(-3900 450);
DISPLAY 1.021277 (-3900 450);
PAINT ORANGE (-3900 450);
FORCEPROP 1 LAST COMMENT_BODY TRUE
J 0
(-3700 675);
DISPLAY 0.978723 (-3700 675);
PAINT ORANGE (-3700 675);
DISPLAY INVISIBLE (-3700 675);
FORCEPROP 2 LAST CDS_LIB mstr_symbols
J 0
(-3725 575);
PAINT MONO (-3725 575);
DISPLAY INVISIBLE (-3725 575);
FORCEADD DESIGN_NOTE..1
(-6400 225);
FORCEPROP 0 LAST L1 SMBUS PULL UP AND SERIES RESISTORS ON SEPARATE PAGE
J 0
(-6575 75);
DISPLAY 1.021277 (-6575 75);
PAINT ORANGE (-6575 75);
FORCEPROP 1 LAST COMMENT_BODY TRUE
J 0
(-6375 325);
DISPLAY 0.978723 (-6375 325);
PAINT ORANGE (-6375 325);
DISPLAY INVISIBLE (-6375 325);
FORCEPROP 2 LAST CDS_LIB mstr_symbols
J 0
(-6400 225);
PAINT ORANGE (-6400 225);
DISPLAY INVISIBLE (-6400 225);
FORCEADD INTEL_CORP_BPAGE..1
(0 0);
FORCEPROP 1 LAST CDS_CON_LAST_MODIFIED Fri Jun 16 17:48:47 2017
J 0
(-1425 325);
DISPLAY 1.340426 (-1425 325);
PAINT ORANGE (-1425 325);
DISPLAY INVISIBLE (-1425 325);
FORCEPROP 1 LAST CUSTOM_TXT_CDS <CURRENT_DESIGN_SHEET> OF <TOTAL_DESIGN_SHEETS>
J 0
(-500 25);
PAINT ORANGE (-500 25);
FORCEPROP 1 LAST CUSTOM_TXT_CDS <CON_LAST_MODIFIED>
J 0
(-4000 100);
PAINT ORANGE (-4000 100);
FORCEPROP 2 LAST CUSTOM_TXT_CDS <XR_PAGE_TITLE>
J 0
(-7890 5250);
DISPLAY 0.638298 (-7890 5250);
PAINT PINK (-7890 5250);
DISPLAY INVISIBLE (-7890 5250);
FORCEPROP 1 LAST SCH_TITLE LEWISBURG 6/11 GPIO A-D
J 0
(-7950 50);
DISPLAY 1.212766 (-7950 50);
PAINT YELLOW (-7950 50);
FORCEPROP 1 LAST COMMENT_BODY TRUE
J 0
(12 12);
DISPLAY 0.638298 (12 12);
PAINT PEACH (12 12);
DISPLAY INVISIBLE (12 12);
FORCEPROP 2 LAST CDS_LIB mstr_symbols
J 0
(0 0);
PAINT ORANGE (0 0);
DISPLAY INVISIBLE (0 0);
FORCEPROP 2 LAST PAGE_BORDER TRUE
J 0
(-7890 5250);
DISPLAY 0.851064 (-7890 5250);
PAINT PINK (-7890 5250);
DISPLAY INVISIBLE (-7890 5250);
FORCEPROP 2 LAST CDS_XR_PAGE_TITLE CR-119 : @BASEBOARD_FAB2_LIB.BASEBOARD_FAB2(SCH_1):PAGE119
J 0
(-7890 5250);
DISPLAY 0.638298 (-7890 5250);
PAINT PINK (-7890 5250);
DISPLAY INVISIBLE (-7890 5250);
FORCEADD CAD_NOTE..1
(-7700 4900);
FORCEPROP 0 LAST L1 PLACE DAMPENING RESISTOR ON LPC CLOCK CLOSE TO PCH
J 0
(-7850 4750);
DISPLAY 1.021277 (-7850 4750);
PAINT ORANGE (-7850 4750);
FORCEPROP 1 LAST COMMENT_BODY TRUE
J 0
(-7675 5000);
DISPLAY 0.978723 (-7675 5000);
PAINT ORANGE (-7675 5000);
DISPLAY INVISIBLE (-7675 5000);
FORCEPROP 2 LAST CDS_LIB mstr_symbols
J 0
(-7700 4900);
PAINT ORANGE (-7700 4900);
DISPLAY INVISIBLE (-7700 4900);
FORCEADD CAD_NOTE..1
(-1200 4750);
FORCEPROP 0 LAST L1 PLACE SERIES TERM RES CLOSE TO PCH
J 0
(-1350 4625);
DISPLAY 0.808511 (-1350 4625);
PAINT ORANGE (-1350 4625);
FORCEPROP 1 LAST COMMENT_BODY TRUE
J 0
(-1175 4850);
DISPLAY 0.978723 (-1175 4850);
PAINT ORANGE (-1175 4850);
DISPLAY INVISIBLE (-1175 4850);
FORCEPROP 2 LAST CDS_LIB mstr_symbols
J 0
(-1200 4750);
PAINT MONO (-1200 4750);
DISPLAY INVISIBLE (-1200 4750);
WIRE 16 -1 (-2700 1650)(-2700 1525);
WIRE 16 -1 (-2700 1525)(-2800 1525);
WIRE 16 -1 (-3950 900)(-3950 1000);
WIRE 16 -1 (-4725 1450)(-4725 1500);
WIRE 16 -1 (-4725 1325)(-4725 1450);
WIRE 16 -1 (-4725 475)(-4725 525);
WIRE 16 -1 (-5175 1100)(-5175 1000);
WIRE 16 -1 (-1700 4850)(-1700 4825);
WIRE 16 -1 (-1700 1700)(-1700 1750);
WIRE 3 682 (-2300 1900)(-2300 1350);
WIRE 3 682 (-1450 1900)(-2300 1900);
WIRE 3 682 (-2300 1350)(-1450 1350);
WIRE 3 682 (-1450 1350)(-1450 1900);
WIRE 16 -1 (-2300 2000)(-825 2000);
FORCEPROP 2 LAST SIG_NAME IRQ_BMC_PCH_NMI_STBY_R_N
J 0
(-2150 2010);
DISPLAY 0.617021 (-2150 2010);
PAINT ORANGE (-2150 2010);
WIRE 16 -1 (-2300 2050)(-825 2050);
FORCEPROP 2 LAST SIG_NAME FM_PWR_LED_N
J 0
(-2150 2060);
DISPLAY 0.617021 (-2150 2060);
PAINT ORANGE (-2150 2060);
WIRE 16 -1 (-2300 2100)(-825 2100);
FORCEPROP 2 LAST SIG_NAME IRQ_HSC_FAULT_N
J 0
(-2150 2110);
DISPLAY 0.617021 (-2150 2110);
PAINT ORANGE (-2150 2110);
WIRE 16 -1 (-2300 2150)(-825 2150);
FORCEPROP 2 LAST SIG_NAME IRQ_MEZZ_LAN_ALERT_N
J 0
(-2150 2160);
DISPLAY 0.617021 (-2150 2160);
PAINT ORANGE (-2150 2160);
WIRE 16 -1 (-2300 2200)(-1550 2200);
FORCEPROP 2 LAST SIG_NAME FM_PCH_PLD_DATA_R
J 0
(-2150 2210);
DISPLAY 0.617021 (-2150 2210);
PAINT ORANGE (-2150 2210);
FORCEPROP 2 LASTPROP $XRERR UNIQUE?
J 0
(-2390 2210);
DISPLAY 0.638298 (-2390 2210);
PAINT MONO (-2390 2210);
DISPLAY INVISIBLE (-2390 2210);
WIRE 16 -1 (-2300 2250)(-825 2250);
FORCEPROP 2 LAST SIG_NAME FM_BMC_ENABLE_N
J 0
(-2150 2260);
DISPLAY 0.617021 (-2150 2260);
PAINT ORANGE (-2150 2260);
WIRE 16 -1 (-2300 2300)(-825 2300);
FORCEPROP 2 LAST SIG_NAME FM_CPLD_BMC_PWRDN_N
J 0
(-2150 2310);
DISPLAY 0.617021 (-2150 2310);
PAINT ORANGE (-2150 2310);
WIRE 16 -1 (-2300 2750)(-825 2750);
FORCEPROP 2 LAST SIG_NAME SGPIO_PCH_SSATA_DOUT0
J 0
(-2150 2760);
DISPLAY 0.617021 (-2150 2760);
PAINT ORANGE (-2150 2760);
WIRE 16 -1 (-2300 2500)(-825 2500);
FORCEPROP 2 LAST SIG_NAME H_CPU0_FAST_WAKE_LVT3_N
J 0
(-2150 2510);
DISPLAY 0.617021 (-2150 2510);
PAINT ORANGE (-2150 2510);
WIRE 16 -1 (-2300 2400)(-825 2400);
FORCEPROP 2 LAST SIG_NAME FM_BMC_FAULT_LED_N
J 0
(-2150 2410);
DISPLAY 0.617021 (-2150 2410);
PAINT ORANGE (-2150 2410);
WIRE 16 -1 (-2300 2350)(-825 2350);
FORCEPROP 2 LAST SIG_NAME FM_BMC_CPLD_GPO
J 0
(-2150 2360);
DISPLAY 0.617021 (-2150 2360);
PAINT ORANGE (-2150 2360);
WIRE 16 -1 (-2300 3000)(-825 3000);
FORCEPROP 2 LAST SIG_NAME FM_BMC_HEARTBEAT_N
J 0
(-2150 3010);
DISPLAY 0.617021 (-2150 3010);
PAINT ORANGE (-2150 3010);
WIRE 16 -1 (-2300 2950)(-1575 2950);
FORCEPROP 2 LAST SIG_NAME FM_ADR_MODE_SEL_R
J 0
(-2150 2960);
DISPLAY 0.617021 (-2150 2960);
PAINT ORANGE (-2150 2960);
FORCEPROP 2 LASTPROP $XRERR UNIQUE?
J 0
(-2390 2960);
DISPLAY 0.638298 (-2390 2960);
PAINT MONO (-2390 2960);
DISPLAY INVISIBLE (-2390 2960);
WIRE 16 -1 (-2300 2900)(-825 2900);
FORCEPROP 2 LAST SIG_NAME FM_XRC_READY_N
J 0
(-2150 2910);
DISPLAY 0.617021 (-2150 2910);
PAINT ORANGE (-2150 2910);
WIRE 16 -1 (-2300 2850)(-825 2850);
FORCEPROP 2 LAST SIG_NAME FM_XRC_PRESENT_N
J 0
(-2150 2860);
DISPLAY 0.617021 (-2150 2860);
PAINT ORANGE (-2150 2860);
WIRE 16 -1 (-825 2800)(-2300 2800);
FORCEPROP 2 LAST SIG_NAME IRQ_OOB_MGMT_RISER_ALERT_N
J 0
(-2185 2810);
DISPLAY 0.638298 (-2185 2810);
PAINT ORANGE (-2185 2810);
WIRE 16 -1 (-825 2700)(-2300 2700);
FORCEPROP 2 LAST SIG_NAME SMB_SLOTX24_PCH_STBY_LVC3_SDA
J 0
(-2185 2710);
DISPLAY 0.638298 (-2185 2710);
PAINT ORANGE (-2185 2710);
WIRE 16 -1 (-2300 2600)(-825 2600);
FORCEPROP 2 LAST SIG_NAME FM_TPM_PRES_RST_N
J 0
(-2160 2610);
DISPLAY 0.638298 (-2160 2610);
PAINT ORANGE (-2160 2610);
WIRE 16 -1 (-1700 1500)(-1700 1450);
WIRE 16 -1 (-2250 1450)(-1700 1450);
FORCEPROP 2 LAST SIG_NAME FM_BMC_ENABLE_N
J 0
(-2200 1460);
DISPLAY 0.617021 (-2200 1460);
PAINT ORANGE (-2200 1460);
FORCEPROP 2 LASTPROP $XR1 119 
J 0
(-2406 1414);
DISPLAY 0.638298 (-2406 1414);
PAINT MONO (-2406 1414);
FORCEPROP 2 LASTPROP $XR0 157 
J 0
(-2406 1450);
DISPLAY 0.638298 (-2406 1450);
PAINT MONO (-2406 1450);
WIRE 16 -1 (-2300 2650)(-825 2650);
FORCEPROP 2 LAST SIG_NAME SMB_SLOTX24_PCH_STBY_LVC3_SCL
J 0
(-2185 2660);
DISPLAY 0.638298 (-2185 2660);
PAINT ORANGE (-2185 2660);
WIRE 16 -1 (-2300 2550)(-825 2550);
FORCEPROP 2 LAST SIG_NAME IRQ_LOM_ALERT_N
J 0
(-2150 2560);
DISPLAY 0.617021 (-2150 2560);
PAINT ORANGE (-2150 2560);
WIRE 16 -1 (-1350 2200)(-825 2200);
FORCEPROP 0 LAST SIG_NAME FM_PCH_PLD_DATA
J 0
(-1260 2210);
DISPLAY 0.617021 (-1260 2210);
PAINT ORANGE (-1260 2210);
WIRE 16 -1 (-3000 1525)(-3450 1525);
FORCEPROP 2 LAST SIG_NAME FM_PWR_LED_A
J 0
(-3360 1535);
DISPLAY 0.617021 (-3360 1535);
PAINT ORANGE (-3360 1535);
FORCEPROP 2 LASTPROP $XRERR UNIQUE?
J 0
(-3600 1535);
DISPLAY 0.638298 (-3600 1535);
PAINT MONO (-3600 1535);
DISPLAY INVISIBLE (-3600 1535);
WIRE 16 -1 (-5175 800)(-5175 625);
WIRE 16 -1 (-4925 625)(-5175 625);
WIRE 16 -1 (-5550 625)(-5175 625);
FORCEPROP 2 LAST SIG_NAME FM_PWR_LED_N
J 0
(-5510 635);
DISPLAY 0.617021 (-5510 635);
PAINT ORANGE (-5510 635);
WIRE 16 -1 (-4725 1100)(-4725 1250);
WIRE 16 -1 (-4725 1100)(-4150 1100);
FORCEPROP 2 LAST SIG_NAME FM_PWR_LED
J 0
(-4585 1110);
DISPLAY 0.617021 (-4585 1110);
PAINT ORANGE (-4585 1110);
FORCEPROP 2 LASTPROP $XRERR UNIQUE?
J 0
(-4825 1110);
DISPLAY 0.638298 (-4825 1110);
PAINT MONO (-4825 1110);
DISPLAY INVISIBLE (-4825 1110);
WIRE 16 -1 (-4725 925)(-4725 1100);
WIRE 16 -1 (-3950 1525)(-3950 1400);
WIRE 16 -1 (-3650 1525)(-3950 1525);
FORCEPROP 2 LAST SIG_NAME FM_PWR_LED_K
J 0
(-4160 1535);
DISPLAY 0.617021 (-4160 1535);
PAINT ORANGE (-4160 1535);
FORCEPROP 2 LASTPROP $XRERR UNIQUE?
J 0
(-4400 1535);
DISPLAY 0.638298 (-4400 1535);
PAINT MONO (-4400 1535);
DISPLAY INVISIBLE (-4400 1535);
WIRE 16 -1 (-7500 4150)(-5900 4150);
FORCEPROP 2 LAST SIG_NAME RST_PCH_SYSRST_BTN_OUT_N
J 0
(-7500 4160);
DISPLAY 0.617021 (-7500 4160);
PAINT ORANGE (-7500 4160);
WIRE 16 -1 (-1375 4100)(-450 4100);
FORCEPROP 2 LAST SIG_NAME FM_PWRBRK_SLOT_N
J 2
(-575 4110);
DISPLAY 0.617021 (-575 4110);
PAINT ORANGE (-575 4110);
WIRE 16 -1 (-1450 4250)(-825 4250);
FORCEPROP 2 LAST SIG_NAME FM_THROTTLE_N
J 0
(-1400 4260);
DISPLAY 0.617021 (-1400 4260);
PAINT ORANGE (-1400 4260);
WIRE 16 -1 (-2300 3650)(-825 3650);
FORCEPROP 2 LAST SIG_NAME FM_PASSWORD_CLEAR_N
J 0
(-2150 3660);
DISPLAY 0.617021 (-2150 3660);
PAINT ORANGE (-2150 3660);
WIRE 16 -1 (-2300 3600)(-825 3600);
FORCEPROP 2 LAST SIG_NAME SMB_PMBUS_BMC_STBY_LVC3_SDA_R1
J 0
(-2150 3610);
DISPLAY 0.617021 (-2150 3610);
PAINT ORANGE (-2150 3610);
WIRE 16 -1 (-2300 3550)(-825 3550);
FORCEPROP 2 LAST SIG_NAME SMB_PMBUS_BMC_STBY_LVC3_SCL_R1
J 0
(-2150 3560);
DISPLAY 0.617021 (-2150 3560);
PAINT ORANGE (-2150 3560);
WIRE 16 -1 (-2300 3500)(-825 3500);
FORCEPROP 2 LAST SIG_NAME IRQ_SML0_ALERT_N
J 0
(-2150 3510);
DISPLAY 0.617021 (-2150 3510);
PAINT ORANGE (-2150 3510);
WIRE 16 -1 (-1100 4150)(-450 4150);
FORCEPROP 2 LAST SIG_NAME FM_PMBUS_ALERT_BUF_EN_N
J 0
(-1025 4160);
DISPLAY 0.617021 (-1025 4160);
PAINT ORANGE (-1025 4160);
WIRE 16 -1 (-2300 3800)(-825 3800);
FORCEPROP 2 LAST SIG_NAME FM_BOARD_REV_ID2
J 0
(-2150 3810);
DISPLAY 0.617021 (-2150 3810);
PAINT ORANGE (-2150 3810);
WIRE 16 -1 (-2300 3750)(-825 3750);
FORCEPROP 2 LAST SIG_NAME FM_PCH_SATA_RAID_KEY
J 0
(-2150 3760);
DISPLAY 0.617021 (-2150 3760);
PAINT ORANGE (-2150 3760);
WIRE 16 -1 (-2300 3700)(-825 3700);
FORCEPROP 2 LAST SIG_NAME FM_CPU1_RC_EN
J 0
(-2150 3710);
DISPLAY 0.617021 (-2150 3710);
PAINT ORANGE (-2150 3710);
WIRE 16 -1 (-2300 3450)(-825 3450);
FORCEPROP 2 LAST SIG_NAME SMB_SMLINK0_STBY_LVC3_SDA_R1
J 0
(-2150 3460);
DISPLAY 0.617021 (-2150 3460);
PAINT ORANGE (-2150 3460);
WIRE 16 -1 (-2300 3400)(-825 3400);
FORCEPROP 2 LAST SIG_NAME SMB_SMLINK0_STBY_LVC3_SCL_R1
J 0
(-2150 3410);
DISPLAY 0.617021 (-2150 3410);
PAINT ORANGE (-2150 3410);
WIRE 16 -1 (-2300 3350)(-825 3350);
FORCEPROP 2 LAST SIG_NAME PU_PCH_TLS_ENABLE_STRAP
J 0
(-2150 3360);
DISPLAY 0.617021 (-2150 3360);
PAINT ORANGE (-2150 3360);
WIRE 16 -1 (-2300 3300)(-825 3300);
FORCEPROP 2 LAST SIG_NAME SMB_HOST_STBY_LVC3_SDA_R1
J 0
(-2150 3310);
DISPLAY 0.617021 (-2150 3310);
PAINT ORANGE (-2150 3310);
WIRE 16 -1 (-2300 3250)(-825 3250);
FORCEPROP 2 LAST SIG_NAME SMB_HOST_STBY_LVC3_SCL_R1
J 0
(-2150 3260);
DISPLAY 0.617021 (-2150 3260);
PAINT ORANGE (-2150 3260);
WIRE 16 -1 (-2300 3150)(-825 3150);
FORCEPROP 2 LAST SIG_NAME FM_CPU0_THERMTRIP_LATCH_LVT3_N
J 0
(-2150 3160);
DISPLAY 0.617021 (-2150 3160);
PAINT ORANGE (-2150 3160);
WIRE 16 -1 (-2300 4050)(-825 4050);
FORCEPROP 2 LAST SIG_NAME FM_SLT_CFG1
J 0
(-2150 4060);
DISPLAY 0.617021 (-2150 4060);
PAINT ORANGE (-2150 4060);
WIRE 16 -1 (-2300 3950)(-825 3950);
FORCEPROP 2 LAST SIG_NAME IRQ_BMC_PCH_SCI_LPC_N
J 0
(-2150 3960);
DISPLAY 0.617021 (-2150 3960);
PAINT ORANGE (-2150 3960);
WIRE 16 -1 (-2300 3850)(-825 3850);
FORCEPROP 2 LAST SIG_NAME FM_BOARD_REV_ID0
J 0
(-2150 3860);
DISPLAY 0.617021 (-2150 3860);
PAINT ORANGE (-2150 3860);
WIRE 16 -1 (-2300 3900)(-825 3900);
FORCEPROP 2 LAST SIG_NAME FM_BOARD_REV_ID1
J 0
(-2150 3910);
DISPLAY 0.617021 (-2150 3910);
PAINT ORANGE (-2150 3910);
WIRE 16 -1 (-2300 4000)(-825 4000);
FORCEPROP 2 LAST SIG_NAME FM_SLT_CFG0
J 0
(-2150 4010);
DISPLAY 0.617021 (-2150 4010);
PAINT ORANGE (-2150 4010);
WIRE 16 -1 (-1700 4100)(-1575 4100);
WIRE 16 -1 (-1700 4625)(-1700 4100);
WIRE 16 -1 (-2300 4100)(-1700 4100);
FORCEPROP 2 LAST SIG_NAME FM_SLT_CFG2_R
J 0
(-2150 4110);
DISPLAY 0.617021 (-2150 4110);
PAINT ORANGE (-2150 4110);
FORCEPROP 2 LASTPROP $XRERR UNIQUE?
J 0
(-2390 4110);
DISPLAY 0.638298 (-2390 4110);
PAINT MONO (-2390 4110);
DISPLAY INVISIBLE (-2390 4110);
WIRE 16 -1 (-2300 4150)(-1300 4150);
FORCEPROP 2 LAST SIG_NAME FM_PMBUS_ALERT_BUF_EN_R_N
J 0
(-2150 4160);
DISPLAY 0.617021 (-2150 4160);
PAINT ORANGE (-2150 4160);
FORCEPROP 2 LASTPROP $XRERR UNIQUE?
J 0
(-2390 4160);
DISPLAY 0.638298 (-2390 4160);
PAINT MONO (-2390 4160);
DISPLAY INVISIBLE (-2390 4160);
WIRE 16 -1 (-2300 4200)(-450 4200);
FORCEPROP 2 LAST SIG_NAME FM_BB_BMC_MP_GPIO
J 0
(-2150 4210);
DISPLAY 0.617021 (-2150 4210);
PAINT ORANGE (-2150 4210);
WIRE 3 682 (-1775 3050)(-2100 3050);
WIRE 3 682 (-1775 3100)(-1775 3050);
WIRE 3 682 (-1775 3100)(-1700 3100);
WIRE 3 682 (-2100 3100)(-1775 3100);
WIRE 16 -1 (-1450 4400)(-825 4400);
FORCEPROP 0 LAST SIG_NAME FM_CPU_CATERR_DLY_LVT3_N
J 2
(-775 4410);
DISPLAY 0.617021 (-775 4410);
PAINT ORANGE (-775 4410);
WIRE 16 -1 (-2300 4350)(-825 4350);
FORCEPROP 2 LAST SIG_NAME IRQ_BMC_PCH_SMI_LPC_N
J 0
(-2150 4360);
DISPLAY 0.617021 (-2150 4360);
PAINT ORANGE (-2150 4360);
WIRE 16 -1 (-2300 4300)(-825 4300);
FORCEPROP 2 LAST SIG_NAME FM_BIOS_POST_CMPLT_N
J 0
(-2150 4310);
DISPLAY 0.617021 (-2150 4310);
PAINT ORANGE (-2150 4310);
WIRE 16 -1 (-2300 4400)(-1650 4400);
FORCEPROP 2 LAST SIG_NAME FM_CPU_CATERR_DLY_LVT3_R_N
J 0
(-2150 4410);
DISPLAY 0.617021 (-2150 4410);
PAINT ORANGE (-2150 4410);
FORCEPROP 2 LASTPROP $XRERR UNIQUE?
J 0
(-2390 4410);
DISPLAY 0.638298 (-2390 4410);
PAINT MONO (-2390 4410);
DISPLAY INVISIBLE (-2390 4410);
WIRE 16 -1 (-2300 4250)(-1650 4250);
FORCEPROP 2 LAST SIG_NAME FM_THROTTLE_R2_N
J 0
(-2150 4260);
DISPLAY 0.617021 (-2150 4260);
PAINT ORANGE (-2150 4260);
FORCEPROP 2 LASTPROP $XRERR UNIQUE?
J 0
(-2390 4260);
DISPLAY 0.638298 (-2390 4260);
PAINT MONO (-2390 4260);
DISPLAY INVISIBLE (-2390 4260);
WIRE 16 -1 (-7500 3600)(-5900 3600);
FORCEPROP 0 LAST SIG_NAME IRQ_PIRQA_SPI_TPM_N
J 0
(-7500 3611);
DISPLAY 0.617021 (-7500 3611);
PAINT ORANGE (-7500 3611);
WIRE 16 -1 (-7500 3550)(-5900 3550);
FORCEPROP 0 LAST SIG_NAME IRQ_LPC_SERIRQ_N
J 0
(-7500 3561);
DISPLAY 0.617021 (-7500 3561);
PAINT ORANGE (-7500 3561);
WIRE 16 -1 (-6925 3450)(-5900 3450);
FORCEPROP 0 LAST SIG_NAME LPC_LAD3_IO3
J 2
(-6000 3461);
DISPLAY 0.617021 (-6000 3461);
PAINT ORANGE (-6000 3461);
FORCEPROP 2 LASTPROP $XRERR UNIQUE?
J 0
(-6240 3461);
DISPLAY 0.638298 (-6240 3461);
PAINT MONO (-6240 3461);
DISPLAY INVISIBLE (-6240 3461);
WIRE 16 -1 (-6925 3400)(-5900 3400);
FORCEPROP 0 LAST SIG_NAME LPC_LAD2_IO2
J 2
(-6000 3411);
DISPLAY 0.617021 (-6000 3411);
PAINT ORANGE (-6000 3411);
FORCEPROP 2 LASTPROP $XRERR UNIQUE?
J 0
(-6240 3411);
DISPLAY 0.638298 (-6240 3411);
PAINT MONO (-6240 3411);
DISPLAY INVISIBLE (-6240 3411);
WIRE 16 -1 (-6925 3300)(-5900 3300);
FORCEPROP 0 LAST SIG_NAME LPC_LAD0_IO0
J 2
(-6000 3311);
DISPLAY 0.617021 (-6000 3311);
PAINT ORANGE (-6000 3311);
FORCEPROP 2 LASTPROP $XRERR UNIQUE?
J 0
(-6240 3311);
DISPLAY 0.638298 (-6240 3311);
PAINT MONO (-6240 3311);
DISPLAY INVISIBLE (-6240 3311);
WIRE 16 -1 (-7325 3250)(-5900 3250);
FORCEPROP 0 LAST SIG_NAME PU_FM_RCIN_N
J 0
(-7300 3261);
DISPLAY 0.617021 (-7300 3261);
PAINT ORANGE (-7300 3261);
WIRE 16 -1 (-6925 3350)(-5900 3350);
FORCEPROP 0 LAST SIG_NAME LPC_LAD1_IO1
J 2
(-6000 3361);
DISPLAY 0.617021 (-6000 3361);
PAINT ORANGE (-6000 3361);
FORCEPROP 2 LASTPROP $XRERR UNIQUE?
J 0
(-6240 3361);
DISPLAY 0.638298 (-6240 3361);
PAINT MONO (-6240 3361);
DISPLAY INVISIBLE (-6240 3361);
WIRE 16 -1 (-7125 3050)(-5900 3050);
FORCEPROP 2 LAST SIG_NAME FM_FAST_PROCHOT_EN_N
J 0
(-7100 3060);
DISPLAY 0.617021 (-7100 3060);
PAINT ORANGE (-7100 3060);
WIRE 16 -1 (-7125 2950)(-5900 2950);
FORCEPROP 2 LAST SIG_NAME FM_BIOS_PREFRB2_GOOD
J 0
(-7100 2960);
DISPLAY 0.617021 (-7100 2960);
PAINT ORANGE (-7100 2960);
WIRE 16 -1 (-7125 3000)(-5900 3000);
FORCEPROP 2 LAST SIG_NAME FM_BIOS_POST_CMPLT_N
J 0
(-7100 3010);
DISPLAY 0.617021 (-7100 3010);
PAINT ORANGE (-7100 3010);
WIRE 16 -1 (-7125 3100)(-5900 3100);
FORCEPROP 2 LAST SIG_NAME FM_USB_P0_EN_BOOT_BIOS_STRAP_N
J 0
(-7100 3110);
DISPLAY 0.617021 (-7100 3110);
PAINT ORANGE (-7100 3110);
WIRE 16 -1 (-7125 3150)(-5900 3150);
FORCEPROP 2 LAST SIG_NAME FM_PCH_BMC_THERMTRIP_EXI_STRAP_N
J 0
(-7100 3160);
DISPLAY 0.617021 (-7100 3160);
PAINT ORANGE (-7100 3160);
WIRE 17 -1 (-7025 3325)(-7025 3375);
WIRE 17 -1 (-7025 3375)(-7025 3425);
WIRE 17 -1 (-7025 3425)(-7025 3475);
WIRE 17 -1 (-7500 3475)(-7025 3475);
FORCEPROP 2 LAST SIG_NAME LPC_LAD_IO<3:0>
J 0
(-7500 3485);
DISPLAY 0.617021 (-7500 3485);
PAINT ORANGE (-7500 3485);
WIRE 16 -1 (-7125 2250)(-5900 2250);
FORCEPROP 2 LAST SIG_NAME IRQ_PVDDQ_DEF_VRHOT_LVT3_N
J 0
(-7100 2260);
DISPLAY 0.617021 (-7100 2260);
PAINT ORANGE (-7100 2260);
WIRE 16 -1 (-7125 2150)(-5900 2150);
FORCEPROP 2 LAST SIG_NAME FM_QAT_EN_N
J 0
(-7100 2160);
DISPLAY 0.617021 (-7100 2160);
PAINT ORANGE (-7100 2160);
WIRE 16 -1 (-7125 2100)(-5900 2100);
FORCEPROP 2 LAST SIG_NAME PU_IRQ_VRALERT_N
J 0
(-7100 2110);
DISPLAY 0.617021 (-7100 2110);
PAINT ORANGE (-7100 2110);
WIRE 16 -1 (-2300 2450)(-825 2450);
FORCEPROP 2 LAST SIG_NAME IRQ_FORCE_NM_THROTTLE_N
J 0
(-2150 2460);
DISPLAY 0.617021 (-2150 2460);
PAINT ORANGE (-2150 2460);
WIRE 16 -1 (-6575 3500)(-5900 3500);
FORCEPROP 0 LAST SIG_NAME LPC_LFRAME_N_CS0_N
J 0
(-6585 3510);
DISPLAY 0.617021 (-6585 3510);
PAINT ORANGE (-6585 3510);
WIRE 16 -1 (-7500 3700)(-6850 3700);
FORCEPROP 2 LAST SIG_NAME CLK_24M_BMC_LPC
J 0
(-7500 3710);
DISPLAY 0.617021 (-7500 3710);
PAINT ORANGE (-7500 3710);
WIRE 16 -1 (-7125 2450)(-5900 2450);
FORCEPROP 0 LAST SIG_NAME FM_PWR_BTN_N
J 0
(-7100 2460);
DISPLAY 0.617021 (-7100 2460);
PAINT ORANGE (-7100 2460);
WIRE 16 -1 (-7125 2400)(-5900 2400);
FORCEPROP 0 LAST SIG_NAME FP_NMI_BTN_N
J 0
(-7100 2410);
DISPLAY 0.617021 (-7100 2410);
PAINT ORANGE (-7100 2410);
WIRE 16 -1 (-7125 2350)(-5900 2350);
FORCEPROP 2 LAST SIG_NAME IRQ_PVDDQ_KLM_VRHOT_LVT3_N
J 0
(-7100 2360);
DISPLAY 0.617021 (-7100 2360);
PAINT ORANGE (-7100 2360);
WIRE 16 -1 (-7125 2300)(-5900 2300);
FORCEPROP 2 LAST SIG_NAME IRQ_PVDDQ_GHJ_VRHOT_LVT3_N
J 0
(-7100 2310);
DISPLAY 0.617021 (-7100 2310);
PAINT ORANGE (-7100 2310);
WIRE 16 -1 (-7125 2200)(-5900 2200);
FORCEPROP 2 LAST SIG_NAME IRQ_PVDDQ_ABC_VRHOT_LVT3_N
J 0
(-7100 2210);
DISPLAY 0.617021 (-7100 2210);
PAINT ORANGE (-7100 2210);
WIRE 16 -1 (-7125 2050)(-5900 2050);
FORCEPROP 2 LAST SIG_NAME VID_PCH_CORE_PVNN_AUX_VID_1
J 0
(-7100 2060);
DISPLAY 0.617021 (-7100 2060);
PAINT ORANGE (-7100 2060);
WIRE 16 -1 (-7125 2900)(-5900 2900);
FORCEPROP 2 LAST SIG_NAME FM_UV_ADR_TRIGGER_EN
J 0
(-7100 2910);
DISPLAY 0.617021 (-7100 2910);
PAINT ORANGE (-7100 2910);
WIRE 16 -1 (-7125 2850)(-5900 2850);
FORCEPROP 0 LAST SIG_NAME FM_PCH_PWRBTN_OUT_N
J 0
(-7100 2860);
DISPLAY 0.617021 (-7100 2860);
PAINT ORANGE (-7100 2860);
WIRE 16 -1 (-7125 2800)(-5900 2800);
FORCEPROP 2 LAST SIG_NAME IRQ_PCH_NIC_ALERT_N
J 0
(-7100 2810);
DISPLAY 0.617021 (-7100 2810);
PAINT ORANGE (-7100 2810);
WIRE 16 -1 (-7125 2750)(-5900 2750);
FORCEPROP 2 LAST SIG_NAME FM_UART_ALERT_N
J 0
(-7100 2760);
DISPLAY 0.617021 (-7100 2760);
PAINT ORANGE (-7100 2760);
WIRE 16 -1 (-7125 2700)(-5900 2700);
FORCEPROP 2 LAST SIG_NAME FM_BIOS_TOP_SWAP_SPKR
J 0
(-7100 2710);
DISPLAY 0.617021 (-7100 2710);
PAINT ORANGE (-7100 2710);
WIRE 16 -1 (-7700 2650)(-5900 2650);
FORCEPROP 2 LAST SIG_NAME RST_PLTRST_N
J 0
(-6575 2660);
DISPLAY 0.617021 (-6575 2660);
PAINT ORANGE (-6575 2660);
WIRE 16 -1 (-7700 2600)(-5900 2600);
FORCEPROP 2 LAST SIG_NAME FM_GLOBAL_RST_WARN_N
J 0
(-6575 2610);
DISPLAY 0.617021 (-6575 2610);
PAINT ORANGE (-6575 2610);
WIRE 16 -1 (-6825 2550)(-5900 2550);
FORCEPROP 2 LAST SIG_NAME FM_PMBUS_ALERT_BUF_EN_R2_N
J 0
(-6800 2560);
DISPLAY 0.617021 (-6800 2560);
PAINT ORANGE (-6800 2560);
FORCEPROP 2 LASTPROP $XRERR UNIQUE?
J 0
(-7040 2560);
DISPLAY 0.638298 (-7040 2560);
PAINT MONO (-7040 2560);
DISPLAY INVISIBLE (-7040 2560);
WIRE 16 -1 (-7700 2500)(-5900 2500);
FORCEPROP 0 LAST SIG_NAME RST_SYSTEM_BTN_N
J 0
(-7675 2510);
DISPLAY 0.617021 (-7675 2510);
PAINT ORANGE (-7675 2510);
WIRE 16 -1 (-7125 2000)(-5900 2000);
FORCEPROP 2 LAST SIG_NAME VID_PCH_CORE_PVNN_AUX_VID_0
J 0
(-7100 2010);
DISPLAY 0.617021 (-7100 2010);
PAINT ORANGE (-7100 2010);
WIRE 16 -1 (-7700 2550)(-7025 2550);
FORCEPROP 2 LAST SIG_NAME FM_PMBUS_ALERT_BUF_EN_N
J 0
(-7675 2560);
DISPLAY 0.617021 (-7675 2560);
PAINT ORANGE (-7675 2560);
WIRE 3 682 (-900 2625)(-900 2725);
WIRE 3 682 (-850 2625)(-900 2625);
WIRE 3 682 (-900 2725)(-850 2725);
WIRE 3 682 (-850 2725)(-850 2625);
WIRE 16 -1 (-1375 2950)(-825 2950);
FORCEPROP 0 LAST SIG_NAME FM_ADR_MODE_SEL
J 0
(-1285 2960);
DISPLAY 0.617021 (-1285 2960);
PAINT ORANGE (-1285 2960);
WIRE 3 682 (-1650 2475)(-1525 2475);
WIRE 3 682 (-1650 2575)(-1650 2475);
WIRE 3 682 (-1675 2575)(-1650 2575);
WIRE 3 682 (-1675 2625)(-1675 2575);
WIRE 3 682 (-1625 2625)(-1675 2625);
WIRE 3 682 (-1650 2575)(-1625 2575);
WIRE 3 682 (-1625 2575)(-1625 2625);
WIRE 16 -1 (-7500 4400)(-7050 4400);
FORCEPROP 2 LAST SIG_NAME FM_BMC_READY_N
J 0
(-7500 4410);
DISPLAY 0.617021 (-7500 4410);
PAINT ORANGE (-7500 4410);
WIRE 16 -1 (-7500 4300)(-6800 4300);
FORCEPROP 2 LAST SIG_NAME FM_OCP_MEZZA_PRES
J 0
(-7500 4310);
DISPLAY 0.617021 (-7500 4310);
PAINT ORANGE (-7500 4310);
WIRE 16 -1 (-7500 3650)(-5900 3650);
FORCEPROP 0 LAST SIG_NAME PU_LPC_CLKRUN_N
J 0
(-7500 3661);
DISPLAY 0.617021 (-7500 3661);
PAINT ORANGE (-7500 3661);
WIRE 16 -1 (-6650 3700)(-5900 3700);
FORCEPROP 2 LAST SIG_NAME CLK_24M_BMC_LPC_R
J 0
(-6485 3710);
DISPLAY 0.617021 (-6485 3710);
PAINT ORANGE (-6485 3710);
FORCEPROP 2 LASTPROP $XRERR UNIQUE?
J 0
(-6725 3710);
DISPLAY 0.638298 (-6725 3710);
PAINT MONO (-6725 3710);
DISPLAY INVISIBLE (-6725 3710);
WIRE 3 682 (-7050 3750)(-6150 3750);
WIRE 16 -1 (-7500 3800)(-5900 3800);
FORCEPROP 0 LAST SIG_NAME PU_LPC_PME_N
J 0
(-7500 3811);
DISPLAY 0.617021 (-7500 3811);
PAINT ORANGE (-7500 3811);
WIRE 16 -1 (-7500 3850)(-5900 3850);
FORCEPROP 0 LAST SIG_NAME PU_IRQ_PCH_SCI_WHEA_N
J 0
(-7500 3861);
DISPLAY 0.617021 (-7500 3861);
PAINT ORANGE (-7500 3861);
WIRE 16 -1 (-7500 3900)(-5900 3900);
FORCEPROP 0 LAST SIG_NAME FM_MB_SLOT_ID0
J 0
(-7500 3910);
DISPLAY 0.617021 (-7500 3910);
PAINT ORANGE (-7500 3910);
WIRE 16 -1 (-7500 3950)(-5900 3950);
FORCEPROP 0 LAST SIG_NAME FM_MB_SLOT_ID1
J 0
(-7500 3960);
DISPLAY 0.617021 (-7500 3960);
PAINT ORANGE (-7500 3960);
WIRE 16 -1 (-7500 4000)(-5900 4000);
FORCEPROP 0 LAST SIG_NAME FM_MB_SLOT_ID2
J 0
(-7500 4010);
DISPLAY 0.617021 (-7500 4010);
PAINT ORANGE (-7500 4010);
WIRE 16 -1 (-5900 4300)(-6600 4300);
FORCEPROP 2 LAST SIG_NAME FM_OCP_MEZZA_PRES_R
J 0
(-6575 4310);
DISPLAY 0.617021 (-6575 4310);
PAINT ORANGE (-6575 4310);
FORCEPROP 2 LASTPROP $XRERR UNIQUE?
J 0
(-6815 4310);
DISPLAY 0.638298 (-6815 4310);
PAINT MONO (-6815 4310);
DISPLAY INVISIBLE (-6815 4310);
WIRE 16 -1 (-5900 4350)(-7500 4350);
FORCEPROP 2 LAST SIG_NAME FM_TPM_PRES_N
J 0
(-7500 4360);
DISPLAY 0.617021 (-7500 4360);
PAINT ORANGE (-7500 4360);
WIRE 3 682 (-6000 4250)(-6250 4250);
WIRE 16 -1 (-6850 4400)(-5900 4400);
FORCEPROP 2 LAST SIG_NAME FM_BMC_READY_R_N
J 0
(-6450 4410);
DISPLAY 0.617021 (-6450 4410);
PAINT ORANGE (-6450 4410);
FORCEPROP 2 LASTPROP $XRERR UNIQUE?
J 0
(-6690 4410);
DISPLAY 0.638298 (-6690 4410);
PAINT MONO (-6690 4410);
DISPLAY INVISIBLE (-6690 4410);
WIRE 16 -1 (-7500 4200)(-5900 4200);
FORCEPROP 0 LAST SIG_NAME FM_ME_RECOVER_N
J 0
(-7500 4211);
DISPLAY 0.617021 (-7500 4211);
PAINT ORANGE (-7500 4211);
WIRE 16 -1 (-7500 4100)(-5900 4100);
FORCEPROP 0 LAST SIG_NAME FM_CPU_BMC_INIT
J 0
(-7500 4111);
DISPLAY 0.617021 (-7500 4111);
PAINT ORANGE (-7500 4111);
WIRE 16 -1 (-7500 4050)(-5900 4050);
FORCEPROP 0 LAST SIG_NAME FM_UART_PRES_N
J 0
(-7500 4061);
DISPLAY 0.617021 (-7500 4061);
PAINT ORANGE (-7500 4061);
DOT 1 (-1775 3100);
DOT 1 (-1650 2575);
DOT 1 (-1700 4100);
DOT 1 (-5175 625);
DOT 1 (-4725 1100);
FORCENOTE
TP FAB3-DVT DELETE 0OHM RES R7W7 20161206
(-6950 4200) 0;
DISPLAY LEFT (-6950 4200);
DISPLAY 0.638298 (-6950 4200);
PAINT RED (-6950 4200);
FORCENOTE
TP FAB3-DVT ADD RES R7W7 20161201
(-6950 4250) 0;
DISPLAY LEFT (-6950 4250);
DISPLAY 0.638298 (-6950 4250);
PAINT RED (-6950 4250);
FORCENOTE
TP FAB3-DVT RESERVE 0OHM R7W13 20161205
(-7050 4650) 0;
DISPLAY LEFT (-7050 4650);
DISPLAY 0.638298 (-7050 4650);
PAINT RED (-7050 4650);
FORCENOTE
TP FAB3-DVT ADD RES R7W15 20161206
(-6800 4550) 0;
DISPLAY LEFT (-6800 4550);
DISPLAY 0.638298 (-6800 4550);
PAINT RED (-6800 4550);
FORCENOTE
TP FAB3-DVT POP R7W13 20161222
(-7050 4700) 0;
DISPLAY LEFT (-7050 4700);
DISPLAY 0.638298 (-7050 4700);
PAINT RED (-7050 4700);
FORCENOTE
TP FAB1 NC (NO USE IE) 0118
(-8150 3750) 0;
DISPLAY LEFT (-8150 3750);
DISPLAY 1.021277 (-8150 3750);
PAINT RED (-8150 3750);
FORCENOTE
TP FAB1 NC 0309
(-1525 2575) 0;
DISPLAY LEFT (-1525 2575);
DISPLAY 0.808511 (-1525 2575);
PAINT RED (-1525 2575);
FORCENOTE
TP FAB3 NOPOP R2W4 1031
(-6800 2500) 0;
DISPLAY LEFT (-6800 2500);
DISPLAY 0.638298 (-6800 2500);
PAINT RED (-6800 2500);
FORCENOTE
ROOM=SB
(-7875 275) 0;
DISPLAY LEFT (-7875 275);
DISPLAY 1.021277 (-7875 275);
PAINT PURPLE (-7875 275);
FORCENOTE
TP FAB3-DVT POP R7W17 20161222
(-1100 4450) 0;
DISPLAY LEFT (-1100 4450);
DISPLAY 0.638298 (-1100 4450);
PAINT RED (-1100 4450);
FORCENOTE
TP FAB1 NC (NO USE IE) 0118
(-1625 3075) 0;
DISPLAY LEFT (-1625 3075);
DISPLAY 0.808511 (-1625 3075);
PAINT RED (-1625 3075);
FORCENOTE
TP FAB3 NOPOP R2W3 1031
(-1300 4200) 0;
DISPLAY LEFT (-1300 4200);
DISPLAY 0.638298 (-1300 4200);
PAINT RED (-1300 4200);
FORCENOTE
TP FAB3-DVT ADD RESERVE R7W17 20161206
(-1650 4350) 0;
DISPLAY LEFT (-1650 4350);
DISPLAY 0.638298 (-1650 4350);
PAINT RED (-1650 4350);
FORCENOTE
TP FAB4 POP R2W3 20170116
(-1400 4050) 0;
DISPLAY LEFT (-1400 4050);
DISPLAY 0.638298 (-1400 4050);
PAINT RED (-1400 4050);
FORCENOTE
TP FAB1 PUT BACK NET 0227
(-1525 2625) 0;
DISPLAY LEFT (-1525 2625);
DISPLAY 0.808511 (-1525 2625);
PAINT RED (-1525 2625);
FORCENOTE
TP FAB1 CHANGE CONNECTION 0310
(-1500 2450) 0;
DISPLAY LEFT (-1500 2450);
DISPLAY 0.638298 (-1500 2450);
PAINT RED (-1500 2450);
FORCENOTE
TP FAB1 PUT BACK NET 0310
(-1525 2525) 0;
DISPLAY LEFT (-1525 2525);
DISPLAY 0.808511 (-1525 2525);
PAINT RED (-1525 2525);
FORCENOTE
TP FAB1 NC (NO USE IE) 0118
(-1525 2675) 0;
DISPLAY LEFT (-1525 2675);
DISPLAY 0.808511 (-1525 2675);
PAINT RED (-1525 2675);
FORCENOTE
TP FAB1 PUT BACK NET 0310
(-1525 2800) 0;
DISPLAY LEFT (-1525 2800);
DISPLAY 0.808511 (-1525 2800);
PAINT RED (-1525 2800);
FORCENOTE
TP FAB1 NC (NO USE IE) 0118
(-1525 2850) 0;
DISPLAY LEFT (-1525 2850);
DISPLAY 0.808511 (-1525 2850);
PAINT RED (-1525 2850);
FORCENOTE
TP FAB4 RESERVE R7W22 20170207
(-2300 1300) 0;
DISPLAY LEFT (-2300 1300);
DISPLAY 0.638298 (-2300 1300);
PAINT RED (-2300 1300);
QUIT
